FILE_TYPE = MACRO_DRAWING;
SET COLOR_WIRE YELLOW;
SET COLOR_PROP ORANGE;
SET COLOR_DOT WHITE;
SET COLOR_ARC YELLOW;
SET COLOR_BODY GREEN;
SET COLOR_NOTE PURPLE;
SET PROP_DISPLAY VALUE;
SET PAGE_NUMBER P115;
FORCEADD OFFPAGE..1
(525 -2750);
FORCEPROP 2 LAST $XR0 114 
J 0
(273 -2750);
DISPLAY 0.638298 (273 -2750);
PAINT MONO (273 -2750);
FORCEPROP 1 LAST COMMENT_BODY TRUE
J 0
(650 -2850);
DISPLAY 0.872340 (650 -2850);
PAINT GREEN (650 -2850);
DISPLAY INVISIBLE (650 -2850);
FORCEPROP 1 LAST OFFPAGE TRUE
J 0
(850 -2875);
DISPLAY 0.872340 (850 -2875);
PAINT GREEN (850 -2875);
DISPLAY INVISIBLE (850 -2875);
FORCEPROP 2 LAST CDS_LIB standard
J 0
(525 -2750);
PAINT MONO (525 -2750);
DISPLAY INVISIBLE (525 -2750);
FORCEPROP 2 LAST PATH I1
J 0
(250 -2700);
DISPLAY 1.021277 (250 -2700);
DISPLAY INVISIBLE (250 -2700);
FORCEADD UNIVERSAL_POWER..1
(1400 -2325);
FORCEPROP 3 LASTPIN (1400 -2375) SIG_NAME P3V3_AUX\g
J 0
(1410 -2365);
DISPLAY 0.659574 (1410 -2365);
PAINT MONO (1410 -2365);
DISPLAY INVISIBLE (1410 -2365);
FORCEPROP 1 LAST HDL_POWER P3V3_AUX
J 1
(1400 -2275);
DISPLAY 0.872340 (1400 -2275);
PAINT GREEN (1400 -2275);
FORCEPROP 2 LAST CDS_LIB logical_power
J 0
(1400 -2325);
DISPLAY INVISIBLE (1400 -2325);
FORCEPROP 1 LAST PATH I10
J 0
(1450 -2300);
DISPLAY 0.872340 (1450 -2300);
PAINT AQUA (1450 -2300);
DISPLAY INVISIBLE (1450 -2300);
FORCEADD Q_RES..1
(1825 -2500);
FORCEPROP 1 LAST PART_NUMBER CS31002FB08
J 0
(1900 -2575);
DISPLAY 0.787234 (1900 -2575);
DISPLAY INVISIBLE (1900 -2575);
FORCEPROP 1 LAST WATTAGE 1/16W
J 2
(1775 -2625);
DISPLAY 0.787234 (1775 -2625);
FORCEPROP 1 LAST VALUE 10K
J 2
(1775 -2575);
DISPLAY 0.787234 (1775 -2575);
FORCEPROP 1 LAST TOLERANCE 1%
J 0
(1800 -2575);
DISPLAY 0.787234 (1800 -2575);
FORCEPROP 1 LAST MATERIAL CHIP
J 0
(1800 -2625);
DISPLAY 0.787234 (1800 -2625);
FORCEPROP 1 LAST PACK_TYPE 0402LF
J 0
(2050 -2625);
DISPLAY 0.787234 (2050 -2625);
FORCEPROP 1 LAST $LOCATION R947
J 0
(1625 -2500);
DISPLAY 0.787234 (1625 -2500);
FORCEPROP 1 LASTPIN (1725 -2500) $PN 1
J 0
(1737 -2488);
DISPLAY 0.787234 (1737 -2488);
PAINT MONO (1737 -2488);
FORCEPROP 1 LASTPIN (1925 -2500) $PN 2
J 0
(1887 -2488);
DISPLAY 0.787234 (1887 -2488);
PAINT MONO (1887 -2488);
FORCEPROP 1 LAST PATH I11
J 0
(1775 -2350);
DISPLAY 0.978723 (1775 -2350);
PAINT WHITE (1775 -2350);
DISPLAY INVISIBLE (1775 -2350);
FORCEPROP 2 LAST CDS_LIB pure_quanta
J 0
(1825 -2500);
DISPLAY INVISIBLE (1825 -2500);
FORCEPROP 2 LAST CDS_LOCATION R947
J 0
(1775 -2300);
DISPLAY 1.021277 (1775 -2300);
DISPLAY INVISIBLE (1775 -2300);
FORCEPROP 0 LAST $SEC 1
J 0
(1625 -2450);
DISPLAY 0.680851 (1625 -2450);
PAINT MONO (1625 -2450);
DISPLAY INVISIBLE (1625 -2450);
FORCEPROP 2 LAST CDS_SEC 1
J 0
(1775 -2300);
DISPLAY 1.021277 (1775 -2300);
DISPLAY INVISIBLE (1775 -2300);
FORCEADD Q_RES..1
(1825 -2125);
FORCEPROP 1 LAST PART_NUMBER CS21002FB06
J 0
(1900 -2200);
DISPLAY 0.510638 (1900 -2200);
DISPLAY INVISIBLE (1900 -2200);
FORCEPROP 1 LAST VALUE 1K
J 2
(1775 -2200);
DISPLAY 0.638298 (1775 -2200);
FORCEPROP 1 LAST WATTAGE 1/16W
J 2
(1775 -2250);
DISPLAY 0.638298 (1775 -2250);
FORCEPROP 1 LAST TOLERANCE 1%
J 0
(1800 -2200);
DISPLAY 0.638298 (1800 -2200);
FORCEPROP 1 LAST MATERIAL CHIP
J 0
(1800 -2250);
DISPLAY 0.638298 (1800 -2250);
FORCEPROP 1 LAST PACK_TYPE 0402LF
J 0
(2050 -2250);
DISPLAY 0.638298 (2050 -2250);
FORCEPROP 1 LAST $LOCATION R2496
J 0
(1575 -2125);
DISPLAY 0.787234 (1575 -2125);
FORCEPROP 1 LASTPIN (1725 -2125) $PN 1
J 0
(1737 -2113);
DISPLAY 0.787234 (1737 -2113);
PAINT MONO (1737 -2113);
FORCEPROP 1 LASTPIN (1925 -2125) $PN 2
J 0
(1887 -2113);
DISPLAY 0.787234 (1887 -2113);
PAINT MONO (1887 -2113);
FORCEPROP 1 LAST PATH I12
J 0
(1775 -1975);
DISPLAY 0.978723 (1775 -1975);
PAINT WHITE (1775 -1975);
DISPLAY INVISIBLE (1775 -1975);
FORCEPROP 2 LAST CDS_LIB pure_quanta
J 0
(1825 -2125);
DISPLAY INVISIBLE (1825 -2125);
FORCEPROP 0 LAST CDS_LOCATION R2496
J 0
(2000 -1975);
DISPLAY 1.021277 (2000 -1975);
DISPLAY INVISIBLE (2000 -1975);
FORCEPROP 0 LAST $SEC 1
J 0
(1575 -2075);
DISPLAY 0.680851 (1575 -2075);
PAINT MONO (1575 -2075);
DISPLAY INVISIBLE (1575 -2075);
FORCEPROP 0 LAST CDS_SEC 1
J 0
(2000 -1975);
DISPLAY 1.021277 (2000 -1975);
DISPLAY INVISIBLE (2000 -1975);
FORCEADD UNIVERSAL_POWER..1
(1400 -1700);
FORCEPROP 3 LASTPIN (1400 -1750) SIG_NAME P3V3_AUX\g
J 0
(1410 -1740);
DISPLAY 0.659574 (1410 -1740);
PAINT MONO (1410 -1740);
DISPLAY INVISIBLE (1410 -1740);
FORCEPROP 1 LAST HDL_POWER P3V3_AUX
J 1
(1400 -1650);
DISPLAY 0.872340 (1400 -1650);
PAINT GREEN (1400 -1650);
FORCEPROP 2 LAST CDS_LIB logical_power
J 0
(1400 -1700);
DISPLAY INVISIBLE (1400 -1700);
FORCEPROP 1 LAST PATH I13
J 0
(1450 -1675);
DISPLAY 0.872340 (1450 -1675);
PAINT AQUA (1450 -1675);
DISPLAY INVISIBLE (1450 -1675);
FORCEADD Q_RES..1
(1825 -1875);
FORCEPROP 1 LAST PART_NUMBER CS31002FB08
J 0
(1875 -1925);
DISPLAY 0.638298 (1875 -1925);
DISPLAY INVISIBLE (1875 -1925);
FORCEPROP 1 LAST PACK_TYPE 0402LF
J 0
(2025 -1975);
DISPLAY 0.638298 (2025 -1975);
FORCEPROP 1 LAST WATTAGE 1/16W
J 2
(1750 -1975);
DISPLAY 0.638298 (1750 -1975);
FORCEPROP 1 LAST VALUE 10K
J 2
(1750 -1925);
DISPLAY 0.638298 (1750 -1925);
FORCEPROP 1 LAST TOLERANCE 1%
J 0
(1775 -1925);
DISPLAY 0.638298 (1775 -1925);
FORCEPROP 1 LAST MATERIAL CHIP
J 0
(1775 -1975);
DISPLAY 0.638298 (1775 -1975);
FORCEPROP 1 LAST $LOCATION R946
J 0
(1600 -1875);
DISPLAY 0.787234 (1600 -1875);
FORCEPROP 1 LASTPIN (1725 -1875) $PN 1
J 0
(1737 -1863);
DISPLAY 0.787234 (1737 -1863);
PAINT MONO (1737 -1863);
FORCEPROP 1 LASTPIN (1925 -1875) $PN 2
J 0
(1887 -1863);
DISPLAY 0.787234 (1887 -1863);
PAINT MONO (1887 -1863);
FORCEPROP 1 LAST PATH I14
J 0
(1775 -1725);
DISPLAY 0.978723 (1775 -1725);
PAINT WHITE (1775 -1725);
DISPLAY INVISIBLE (1775 -1725);
FORCEPROP 2 LAST CDS_LIB pure_quanta
J 0
(1825 -1875);
DISPLAY INVISIBLE (1825 -1875);
FORCEPROP 2 LAST CDS_LOCATION R946
J 0
(1775 -1675);
DISPLAY 1.021277 (1775 -1675);
DISPLAY INVISIBLE (1775 -1675);
FORCEPROP 0 LAST $SEC 1
J 0
(1600 -1825);
DISPLAY 0.680851 (1600 -1825);
PAINT MONO (1600 -1825);
DISPLAY INVISIBLE (1600 -1825);
FORCEPROP 2 LAST CDS_SEC 1
J 0
(1775 -1675);
DISPLAY 1.021277 (1775 -1675);
DISPLAY INVISIBLE (1775 -1675);
FORCEADD UNIVERSAL_POWER..1
(1400 -1075);
FORCEPROP 3 LASTPIN (1400 -1125) SIG_NAME P3V3_AUX\g
J 0
(1410 -1115);
DISPLAY 0.659574 (1410 -1115);
PAINT MONO (1410 -1115);
DISPLAY INVISIBLE (1410 -1115);
FORCEPROP 1 LAST HDL_POWER P3V3_AUX
J 1
(1400 -1025);
DISPLAY 0.872340 (1400 -1025);
PAINT GREEN (1400 -1025);
FORCEPROP 2 LAST CDS_LIB logical_power
J 0
(1400 -1075);
DISPLAY INVISIBLE (1400 -1075);
FORCEPROP 1 LAST PATH I15
J 0
(1450 -1050);
DISPLAY 0.872340 (1450 -1050);
PAINT AQUA (1450 -1050);
DISPLAY INVISIBLE (1450 -1050);
FORCEADD Q_RES..1
(1825 -1250);
FORCEPROP 1 LAST PART_NUMBER CS31002FB08
J 0
(1925 -1300);
DISPLAY 0.638298 (1925 -1300);
DISPLAY INVISIBLE (1925 -1300);
FORCEPROP 1 LAST TOLERANCE 1%
J 0
(1825 -1300);
DISPLAY 0.638298 (1825 -1300);
FORCEPROP 1 LAST MATERIAL CHIP
J 0
(1825 -1350);
DISPLAY 0.638298 (1825 -1350);
FORCEPROP 1 LAST PACK_TYPE 0402LF
J 0
(2075 -1350);
DISPLAY 0.638298 (2075 -1350);
FORCEPROP 1 LAST VALUE 10K
J 2
(1800 -1300);
DISPLAY 0.638298 (1800 -1300);
FORCEPROP 1 LAST WATTAGE 1/16W
J 2
(1800 -1350);
DISPLAY 0.638298 (1800 -1350);
FORCEPROP 1 LAST $LOCATION R945
J 0
(1600 -1250);
DISPLAY 0.787234 (1600 -1250);
FORCEPROP 1 LASTPIN (1725 -1250) $PN 1
J 0
(1737 -1238);
DISPLAY 0.787234 (1737 -1238);
PAINT MONO (1737 -1238);
FORCEPROP 1 LASTPIN (1925 -1250) $PN 2
J 0
(1887 -1238);
DISPLAY 0.787234 (1887 -1238);
PAINT MONO (1887 -1238);
FORCEPROP 1 LAST PATH I16
J 0
(1775 -1100);
DISPLAY 0.978723 (1775 -1100);
PAINT WHITE (1775 -1100);
DISPLAY INVISIBLE (1775 -1100);
FORCEPROP 2 LAST CDS_LIB pure_quanta
J 0
(1825 -1250);
DISPLAY INVISIBLE (1825 -1250);
FORCEPROP 2 LAST CDS_LOCATION R945
J 0
(1775 -1050);
DISPLAY 1.021277 (1775 -1050);
DISPLAY INVISIBLE (1775 -1050);
FORCEPROP 0 LAST $SEC 1
J 0
(1600 -1200);
DISPLAY 0.680851 (1600 -1200);
PAINT MONO (1600 -1200);
DISPLAY INVISIBLE (1600 -1200);
FORCEPROP 2 LAST CDS_SEC 1
J 0
(1775 -1050);
DISPLAY 1.021277 (1775 -1050);
DISPLAY INVISIBLE (1775 -1050);
FORCEADD Q_RES..1
(1825 -1500);
FORCEPROP 1 LAST PART_NUMBER CS21002FB06
J 0
(1975 -1550);
DISPLAY 0.638298 (1975 -1550);
DISPLAY INVISIBLE (1975 -1550);
FORCEPROP 1 LAST MATERIAL CHIP
J 0
(1875 -1600);
DISPLAY 0.638298 (1875 -1600);
FORCEPROP 1 LAST TOLERANCE 1%
J 0
(1875 -1550);
DISPLAY 0.638298 (1875 -1550);
FORCEPROP 1 LAST VALUE 1K
J 2
(1850 -1550);
DISPLAY 0.638298 (1850 -1550);
FORCEPROP 1 LAST PACK_TYPE 0402LF
J 0
(2125 -1600);
DISPLAY 0.638298 (2125 -1600);
FORCEPROP 1 LAST WATTAGE 1/16W
J 2
(1850 -1600);
DISPLAY 0.638298 (1850 -1600);
FORCEPROP 1 LAST $LOCATION R2495
J 0
(1575 -1500);
DISPLAY 0.787234 (1575 -1500);
FORCEPROP 1 LASTPIN (1725 -1500) $PN 1
J 0
(1737 -1488);
DISPLAY 0.787234 (1737 -1488);
PAINT MONO (1737 -1488);
FORCEPROP 1 LASTPIN (1925 -1500) $PN 2
J 0
(1887 -1488);
DISPLAY 0.787234 (1887 -1488);
PAINT MONO (1887 -1488);
FORCEPROP 1 LAST PATH I17
J 0
(1775 -1350);
DISPLAY 0.978723 (1775 -1350);
PAINT WHITE (1775 -1350);
DISPLAY INVISIBLE (1775 -1350);
FORCEPROP 2 LAST CDS_LIB pure_quanta
J 0
(1825 -1500);
DISPLAY INVISIBLE (1825 -1500);
FORCEPROP 0 LAST CDS_LOCATION R2495
J 0
(2000 -1350);
DISPLAY 1.021277 (2000 -1350);
DISPLAY INVISIBLE (2000 -1350);
FORCEPROP 0 LAST $SEC 1
J 0
(1575 -1450);
DISPLAY 0.680851 (1575 -1450);
PAINT MONO (1575 -1450);
DISPLAY INVISIBLE (1575 -1450);
FORCEPROP 0 LAST CDS_SEC 1
J 0
(2000 -1350);
DISPLAY 1.021277 (2000 -1350);
DISPLAY INVISIBLE (2000 -1350);
FORCEADD Q_RES..1
(1825 -875);
FORCEPROP 1 LAST PART_NUMBER CS21002FB06
J 0
(1950 -925);
DISPLAY 0.638298 (1950 -925);
DISPLAY INVISIBLE (1950 -925);
FORCEPROP 1 LAST PACK_TYPE 0402LF
J 0
(2100 -975);
DISPLAY 0.638298 (2100 -975);
FORCEPROP 1 LAST TOLERANCE 1%
J 0
(1850 -925);
DISPLAY 0.638298 (1850 -925);
FORCEPROP 1 LAST MATERIAL CHIP
J 0
(1850 -975);
DISPLAY 0.638298 (1850 -975);
FORCEPROP 1 LAST VALUE 1K
J 2
(1825 -925);
DISPLAY 0.638298 (1825 -925);
FORCEPROP 1 LAST WATTAGE 1/16W
J 2
(1825 -975);
DISPLAY 0.638298 (1825 -975);
FORCEPROP 1 LAST $LOCATION R2494
J 0
(1600 -875);
DISPLAY 0.787234 (1600 -875);
FORCEPROP 1 LASTPIN (1725 -875) $PN 1
J 0
(1737 -863);
DISPLAY 0.787234 (1737 -863);
PAINT MONO (1737 -863);
FORCEPROP 1 LASTPIN (1925 -875) $PN 2
J 0
(1887 -863);
DISPLAY 0.787234 (1887 -863);
PAINT MONO (1887 -863);
FORCEPROP 1 LAST PATH I18
J 0
(1775 -725);
DISPLAY 0.978723 (1775 -725);
PAINT WHITE (1775 -725);
DISPLAY INVISIBLE (1775 -725);
FORCEPROP 2 LAST CDS_LIB pure_quanta
J 0
(1825 -875);
DISPLAY INVISIBLE (1825 -875);
FORCEPROP 0 LAST CDS_LOCATION R2494
J 0
(2000 -725);
DISPLAY 1.021277 (2000 -725);
DISPLAY INVISIBLE (2000 -725);
FORCEPROP 0 LAST $SEC 1
J 0
(1600 -825);
DISPLAY 0.680851 (1600 -825);
PAINT MONO (1600 -825);
DISPLAY INVISIBLE (1600 -825);
FORCEPROP 0 LAST CDS_SEC 1
J 0
(2000 -725);
DISPLAY 1.021277 (2000 -725);
DISPLAY INVISIBLE (2000 -725);
FORCEADD Q_RES..1
(1825 -625);
FORCEPROP 1 LAST PART_NUMBER CS31002FB08
J 0
(1925 -700);
DISPLAY 0.638298 (1925 -700);
DISPLAY INVISIBLE (1925 -700);
FORCEPROP 1 LAST WATTAGE 1/16W
J 2
(1800 -750);
DISPLAY 0.638298 (1800 -750);
FORCEPROP 1 LAST PACK_TYPE 0402LF
J 0
(2075 -750);
DISPLAY 0.638298 (2075 -750);
FORCEPROP 1 LAST VALUE 10K
J 2
(1800 -700);
DISPLAY 0.638298 (1800 -700);
FORCEPROP 1 LAST TOLERANCE 1%
J 0
(1825 -700);
DISPLAY 0.638298 (1825 -700);
FORCEPROP 1 LAST MATERIAL CHIP
J 0
(1825 -750);
DISPLAY 0.638298 (1825 -750);
FORCEPROP 1 LAST $LOCATION R944
J 0
(1625 -625);
DISPLAY 0.787234 (1625 -625);
FORCEPROP 1 LASTPIN (1725 -625) $PN 1
J 0
(1737 -613);
DISPLAY 0.787234 (1737 -613);
PAINT MONO (1737 -613);
FORCEPROP 1 LASTPIN (1925 -625) $PN 2
J 0
(1887 -613);
DISPLAY 0.787234 (1887 -613);
PAINT MONO (1887 -613);
FORCEPROP 1 LAST PATH I19
J 0
(1775 -475);
DISPLAY 0.978723 (1775 -475);
PAINT WHITE (1775 -475);
DISPLAY INVISIBLE (1775 -475);
FORCEPROP 2 LAST CDS_LIB pure_quanta
J 0
(1825 -625);
DISPLAY INVISIBLE (1825 -625);
FORCEPROP 2 LAST CDS_LOCATION R944
J 0
(1775 -425);
DISPLAY 1.021277 (1775 -425);
DISPLAY INVISIBLE (1775 -425);
FORCEPROP 0 LAST $SEC 1
J 0
(1625 -575);
DISPLAY 0.680851 (1625 -575);
PAINT MONO (1625 -575);
DISPLAY INVISIBLE (1625 -575);
FORCEPROP 2 LAST CDS_SEC 1
J 0
(1775 -425);
DISPLAY 1.021277 (1775 -425);
DISPLAY INVISIBLE (1775 -425);
FORCEADD OFFPAGE..1
(525 -2125);
FORCEPROP 2 LAST $XR0 114 
J 0
(273 -2125);
DISPLAY 0.638298 (273 -2125);
PAINT MONO (273 -2125);
FORCEPROP 2 LAST CDS_LIB standard
J 0
(525 -2125);
PAINT MONO (525 -2125);
DISPLAY INVISIBLE (525 -2125);
FORCEPROP 1 LAST OFFPAGE TRUE
J 0
(850 -2250);
DISPLAY 0.872340 (850 -2250);
PAINT GREEN (850 -2250);
DISPLAY INVISIBLE (850 -2250);
FORCEPROP 1 LAST COMMENT_BODY TRUE
J 0
(650 -2225);
DISPLAY 0.872340 (650 -2225);
PAINT GREEN (650 -2225);
DISPLAY INVISIBLE (650 -2225);
FORCEPROP 2 LAST PATH I2
J 0
(250 -2075);
DISPLAY 1.021277 (250 -2075);
DISPLAY INVISIBLE (250 -2075);
FORCEADD UNIVERSAL_POWER..1
(1400 -450);
FORCEPROP 3 LASTPIN (1400 -500) SIG_NAME P3V3_AUX\g
J 0
(1410 -490);
DISPLAY 0.659574 (1410 -490);
PAINT MONO (1410 -490);
DISPLAY INVISIBLE (1410 -490);
FORCEPROP 1 LAST HDL_POWER P3V3_AUX
J 1
(1400 -400);
DISPLAY 0.872340 (1400 -400);
PAINT GREEN (1400 -400);
FORCEPROP 2 LAST CDS_LIB logical_power
J 0
(1400 -450);
DISPLAY INVISIBLE (1400 -450);
FORCEPROP 1 LAST PATH I20
J 0
(1450 -425);
DISPLAY 0.872340 (1450 -425);
PAINT AQUA (1450 -425);
DISPLAY INVISIBLE (1450 -425);
FORCEADD SCHOTTKY_12..1
(4100 -2500);
FORCEPROP 1 LAST PART_NUMBER BC000530Z41
J 0
(4025 -2375);
DISPLAY 0.574468 (4025 -2375);
PAINT GREEN (4025 -2375);
DISPLAY INVISIBLE (4025 -2375);
FORCEPROP 2 LAST PART_TYPE SMLF
J 0
(4025 -2225);
DISPLAY 0.808511 (4025 -2225);
FORCEPROP 1 LAST MATERIAL IC
J 0
(4025 -2425);
DISPLAY 0.574468 (4025 -2425);
PAINT GREEN (4025 -2425);
FORCEPROP 2 LAST VALUE B0530WS7F
J 0
(4025 -2275);
DISPLAY 0.808511 (4025 -2275);
FORCEPROP 1 LAST $LOCATION D49
J 0
(4025 -2325);
DISPLAY 0.574468 (4025 -2325);
PAINT GREEN (4025 -2325);
FORCEPROP 0 LASTPIN (3975 -2500) $PN 1
J 2
(3965 -2490);
DISPLAY 0.680851 (3965 -2490);
PAINT MONO (3965 -2490);
FORCEPROP 0 LASTPIN (4225 -2500) $PN 2
J 0
(4235 -2490);
DISPLAY 0.680851 (4235 -2490);
PAINT MONO (4235 -2490);
FORCEPROP 1 LAST CDS_LMAN_SYM_OUTLINE -75,50,75,-50
J 0
(4100 -2500);
DISPLAY 0.468085 (4100 -2500);
PAINT GREEN (4100 -2500);
DISPLAY INVISIBLE (4100 -2500);
FORCEPROP 1 LAST NEEDS_NO_SIZE TRUE
J 0
(4175 -2550);
DISPLAY 0.468085 (4175 -2550);
PAINT GREEN (4175 -2550);
DISPLAY INVISIBLE (4175 -2550);
FORCEPROP 2 LAST CDS_LIB pure_quanta
J 0
(4100 -2500);
DISPLAY INVISIBLE (4100 -2500);
FORCEPROP 1 LAST PATH I22
J 0
(4100 -2500);
DISPLAY 0.723404 (4100 -2500);
PAINT GREEN (4100 -2500);
DISPLAY INVISIBLE (4100 -2500);
FORCEPROP 0 LAST CDS_LOCATION D49
J 0
(4025 -2175);
DISPLAY 1.021277 (4025 -2175);
DISPLAY INVISIBLE (4025 -2175);
FORCEPROP 0 LAST $SEC 1
J 0
(4025 -2175);
DISPLAY 0.680851 (4025 -2175);
PAINT MONO (4025 -2175);
DISPLAY INVISIBLE (4025 -2175);
FORCEPROP 0 LAST CDS_SEC 1
J 0
(4025 -2175);
DISPLAY 1.021277 (4025 -2175);
DISPLAY INVISIBLE (4025 -2175);
FORCEADD UNIVERSAL_POWER..1
(4725 -2325);
FORCEPROP 3 LASTPIN (4725 -2375) SIG_NAME P3V3_AUX\g
J 0
(4735 -2365);
DISPLAY 0.659574 (4735 -2365);
PAINT MONO (4735 -2365);
DISPLAY INVISIBLE (4735 -2365);
FORCEPROP 1 LAST HDL_POWER P3V3_AUX
J 1
(4725 -2275);
DISPLAY 0.872340 (4725 -2275);
PAINT GREEN (4725 -2275);
FORCEPROP 2 LAST CDS_LIB logical_power
J 0
(4725 -2325);
DISPLAY INVISIBLE (4725 -2325);
FORCEPROP 1 LAST PATH I24
J 0
(4775 -2300);
DISPLAY 0.872340 (4775 -2300);
PAINT AQUA (4775 -2300);
DISPLAY INVISIBLE (4775 -2300);
FORCEADD SCHOTTKY_12..1
(4100 -1875);
FORCEPROP 1 LAST PART_NUMBER BC000530Z41
J 0
(4025 -1750);
DISPLAY 0.574468 (4025 -1750);
PAINT GREEN (4025 -1750);
DISPLAY INVISIBLE (4025 -1750);
FORCEPROP 2 LAST PART_TYPE SMLF
J 0
(4025 -1600);
DISPLAY 0.808511 (4025 -1600);
FORCEPROP 1 LAST MATERIAL IC
J 0
(4025 -1800);
DISPLAY 0.574468 (4025 -1800);
PAINT GREEN (4025 -1800);
FORCEPROP 2 LAST VALUE B0530WS7F
J 0
(4025 -1650);
DISPLAY 0.808511 (4025 -1650);
FORCEPROP 1 LAST $LOCATION D48
J 0
(4025 -1700);
DISPLAY 0.574468 (4025 -1700);
PAINT GREEN (4025 -1700);
FORCEPROP 0 LASTPIN (3975 -1875) $PN 1
J 2
(3965 -1865);
DISPLAY 0.680851 (3965 -1865);
PAINT MONO (3965 -1865);
FORCEPROP 0 LASTPIN (4225 -1875) $PN 2
J 0
(4235 -1865);
DISPLAY 0.680851 (4235 -1865);
PAINT MONO (4235 -1865);
FORCEPROP 2 LAST CDS_LIB pure_quanta
J 0
(4100 -1875);
DISPLAY INVISIBLE (4100 -1875);
FORCEPROP 1 LAST NEEDS_NO_SIZE TRUE
J 0
(4175 -1925);
DISPLAY 0.468085 (4175 -1925);
PAINT GREEN (4175 -1925);
DISPLAY INVISIBLE (4175 -1925);
FORCEPROP 1 LAST CDS_LMAN_SYM_OUTLINE -75,50,75,-50
J 0
(4100 -1875);
DISPLAY 0.468085 (4100 -1875);
PAINT GREEN (4100 -1875);
DISPLAY INVISIBLE (4100 -1875);
FORCEPROP 1 LAST PATH I25
J 0
(4100 -1875);
DISPLAY 0.723404 (4100 -1875);
PAINT GREEN (4100 -1875);
DISPLAY INVISIBLE (4100 -1875);
FORCEPROP 0 LAST CDS_LOCATION D48
J 0
(4025 -1550);
DISPLAY 1.021277 (4025 -1550);
DISPLAY INVISIBLE (4025 -1550);
FORCEPROP 0 LAST $SEC 1
J 0
(4025 -1550);
DISPLAY 0.680851 (4025 -1550);
PAINT MONO (4025 -1550);
DISPLAY INVISIBLE (4025 -1550);
FORCEPROP 0 LAST CDS_SEC 1
J 0
(4025 -1550);
DISPLAY 1.021277 (4025 -1550);
DISPLAY INVISIBLE (4025 -1550);
FORCEADD SCHOTTKY_12..1
(4100 -1250);
FORCEPROP 1 LAST PART_NUMBER BC000530Z41
J 0
(4025 -1125);
DISPLAY 0.574468 (4025 -1125);
PAINT GREEN (4025 -1125);
DISPLAY INVISIBLE (4025 -1125);
FORCEPROP 2 LAST VALUE B0530WS7F
J 0
(4025 -1025);
DISPLAY 0.808511 (4025 -1025);
FORCEPROP 2 LAST PART_TYPE SMLF
J 0
(4025 -975);
DISPLAY 0.808511 (4025 -975);
FORCEPROP 1 LAST MATERIAL IC
J 0
(4025 -1175);
DISPLAY 0.574468 (4025 -1175);
PAINT GREEN (4025 -1175);
FORCEPROP 1 LAST $LOCATION D47
J 0
(4025 -1075);
DISPLAY 0.574468 (4025 -1075);
PAINT GREEN (4025 -1075);
FORCEPROP 0 LASTPIN (3975 -1250) $PN 1
J 2
(3965 -1240);
DISPLAY 0.680851 (3965 -1240);
PAINT MONO (3965 -1240);
FORCEPROP 0 LASTPIN (4225 -1250) $PN 2
J 0
(4235 -1240);
DISPLAY 0.680851 (4235 -1240);
PAINT MONO (4235 -1240);
FORCEPROP 1 LAST CDS_LMAN_SYM_OUTLINE -75,50,75,-50
J 0
(4100 -1250);
DISPLAY 0.468085 (4100 -1250);
PAINT GREEN (4100 -1250);
DISPLAY INVISIBLE (4100 -1250);
FORCEPROP 1 LAST NEEDS_NO_SIZE TRUE
J 0
(4175 -1300);
DISPLAY 0.468085 (4175 -1300);
PAINT GREEN (4175 -1300);
DISPLAY INVISIBLE (4175 -1300);
FORCEPROP 2 LAST CDS_LIB pure_quanta
J 0
(4100 -1250);
DISPLAY INVISIBLE (4100 -1250);
FORCEPROP 1 LAST PATH I27
J 0
(4100 -1250);
DISPLAY 0.723404 (4100 -1250);
PAINT GREEN (4100 -1250);
DISPLAY INVISIBLE (4100 -1250);
FORCEPROP 0 LAST CDS_LOCATION D47
J 0
(4025 -925);
DISPLAY 1.021277 (4025 -925);
DISPLAY INVISIBLE (4025 -925);
FORCEPROP 0 LAST $SEC 1
J 0
(4025 -925);
DISPLAY 0.680851 (4025 -925);
PAINT MONO (4025 -925);
DISPLAY INVISIBLE (4025 -925);
FORCEPROP 0 LAST CDS_SEC 1
J 0
(4025 -925);
DISPLAY 1.021277 (4025 -925);
DISPLAY INVISIBLE (4025 -925);
FORCEADD SCHOTTKY_12..1
(4100 -625);
FORCEPROP 1 LAST PART_NUMBER BC000530Z41
J 0
(4025 -500);
DISPLAY 0.574468 (4025 -500);
PAINT GREEN (4025 -500);
DISPLAY INVISIBLE (4025 -500);
FORCEPROP 2 LAST PART_TYPE SMLF
J 0
(4025 -350);
DISPLAY 0.808511 (4025 -350);
FORCEPROP 2 LAST VALUE B0530WS7F
J 0
(4025 -400);
DISPLAY 0.808511 (4025 -400);
FORCEPROP 1 LAST MATERIAL IC
J 0
(4025 -550);
DISPLAY 0.574468 (4025 -550);
PAINT GREEN (4025 -550);
FORCEPROP 1 LAST $LOCATION D46
J 0
(4025 -450);
DISPLAY 0.574468 (4025 -450);
PAINT GREEN (4025 -450);
FORCEPROP 0 LASTPIN (3975 -625) $PN 1
J 2
(3965 -615);
DISPLAY 0.680851 (3965 -615);
PAINT MONO (3965 -615);
FORCEPROP 0 LASTPIN (4225 -625) $PN 2
J 0
(4235 -615);
DISPLAY 0.680851 (4235 -615);
PAINT MONO (4235 -615);
FORCEPROP 2 LAST CDS_LIB pure_quanta
J 0
(4100 -625);
DISPLAY INVISIBLE (4100 -625);
FORCEPROP 1 LAST NEEDS_NO_SIZE TRUE
J 0
(4175 -675);
DISPLAY 0.468085 (4175 -675);
PAINT GREEN (4175 -675);
DISPLAY INVISIBLE (4175 -675);
FORCEPROP 1 LAST CDS_LMAN_SYM_OUTLINE -75,50,75,-50
J 0
(4100 -625);
DISPLAY 0.468085 (4100 -625);
PAINT GREEN (4100 -625);
DISPLAY INVISIBLE (4100 -625);
FORCEPROP 1 LAST PATH I29
J 0
(4100 -625);
DISPLAY 0.723404 (4100 -625);
PAINT GREEN (4100 -625);
DISPLAY INVISIBLE (4100 -625);
FORCEPROP 0 LAST CDS_LOCATION D46
J 0
(4025 -300);
DISPLAY 1.021277 (4025 -300);
DISPLAY INVISIBLE (4025 -300);
FORCEPROP 0 LAST $SEC 1
J 0
(4025 -300);
DISPLAY 0.680851 (4025 -300);
PAINT MONO (4025 -300);
DISPLAY INVISIBLE (4025 -300);
FORCEPROP 0 LAST CDS_SEC 1
J 0
(4025 -300);
DISPLAY 1.021277 (4025 -300);
DISPLAY INVISIBLE (4025 -300);
FORCEADD OFFPAGE..1
(525 -1500);
FORCEPROP 2 LAST $XR0 114 
J 0
(273 -1500);
DISPLAY 0.638298 (273 -1500);
PAINT MONO (273 -1500);
FORCEPROP 1 LAST COMMENT_BODY TRUE
J 0
(650 -1600);
DISPLAY 0.872340 (650 -1600);
PAINT GREEN (650 -1600);
DISPLAY INVISIBLE (650 -1600);
FORCEPROP 1 LAST OFFPAGE TRUE
J 0
(850 -1625);
DISPLAY 0.872340 (850 -1625);
PAINT GREEN (850 -1625);
DISPLAY INVISIBLE (850 -1625);
FORCEPROP 2 LAST CDS_LIB standard
J 0
(525 -1500);
PAINT MONO (525 -1500);
DISPLAY INVISIBLE (525 -1500);
FORCEPROP 2 LAST PATH I3
J 0
(250 -1450);
DISPLAY 1.021277 (250 -1450);
DISPLAY INVISIBLE (250 -1450);
FORCEADD UNIVERSAL_POWER..1
(4725 -1700);
FORCEPROP 3 LASTPIN (4725 -1750) SIG_NAME P3V3_AUX\g
J 0
(4735 -1740);
DISPLAY 0.659574 (4735 -1740);
PAINT MONO (4735 -1740);
DISPLAY INVISIBLE (4735 -1740);
FORCEPROP 1 LAST HDL_POWER P3V3_AUX
J 1
(4725 -1650);
DISPLAY 0.872340 (4725 -1650);
PAINT GREEN (4725 -1650);
FORCEPROP 2 LAST CDS_LIB logical_power
J 0
(4725 -1700);
DISPLAY INVISIBLE (4725 -1700);
FORCEPROP 1 LAST PATH I30
J 0
(4775 -1675);
DISPLAY 0.872340 (4775 -1675);
PAINT AQUA (4775 -1675);
DISPLAY INVISIBLE (4775 -1675);
FORCEADD UNIVERSAL_POWER..1
(4725 -1075);
FORCEPROP 3 LASTPIN (4725 -1125) SIG_NAME P3V3_AUX\g
J 0
(4735 -1115);
DISPLAY 0.659574 (4735 -1115);
PAINT MONO (4735 -1115);
DISPLAY INVISIBLE (4735 -1115);
FORCEPROP 1 LAST HDL_POWER P3V3_AUX
J 1
(4725 -1025);
DISPLAY 0.872340 (4725 -1025);
PAINT GREEN (4725 -1025);
FORCEPROP 2 LAST CDS_LIB logical_power
J 0
(4725 -1075);
DISPLAY INVISIBLE (4725 -1075);
FORCEPROP 1 LAST PATH I31
J 0
(4775 -1050);
DISPLAY 0.872340 (4775 -1050);
PAINT AQUA (4775 -1050);
DISPLAY INVISIBLE (4775 -1050);
FORCEADD UNIVERSAL_POWER..1
(4725 -450);
FORCEPROP 3 LASTPIN (4725 -500) SIG_NAME P3V3_AUX\g
J 0
(4735 -490);
DISPLAY 0.659574 (4735 -490);
PAINT MONO (4735 -490);
DISPLAY INVISIBLE (4735 -490);
FORCEPROP 1 LAST HDL_POWER P3V3_AUX
J 1
(4725 -400);
DISPLAY 0.872340 (4725 -400);
PAINT GREEN (4725 -400);
FORCEPROP 2 LAST CDS_LIB logical_power
J 0
(4725 -450);
DISPLAY INVISIBLE (4725 -450);
FORCEPROP 1 LAST PATH I32
J 0
(4775 -425);
DISPLAY 0.872340 (4775 -425);
PAINT AQUA (4775 -425);
DISPLAY INVISIBLE (4775 -425);
FORCEADD OFFPAGE..2
(5775 -2750);
FORCEPROP 2 LAST $XR0 214 
J 0
(5964 -2750);
DISPLAY 0.638298 (5964 -2750);
PAINT MONO (5964 -2750);
FORCEPROP 1 LAST COMMENT_BODY TRUE
J 0
(5730 -2845);
DISPLAY 0.872340 (5730 -2845);
PAINT GREEN (5730 -2845);
DISPLAY INVISIBLE (5730 -2845);
FORCEPROP 1 LAST OFFPAGE TRUE
J 0
(6100 -2875);
DISPLAY 0.872340 (6100 -2875);
PAINT GREEN (6100 -2875);
DISPLAY INVISIBLE (6100 -2875);
FORCEPROP 2 LAST CDS_LIB standard
J 0
(5775 -2750);
DISPLAY INVISIBLE (5775 -2750);
FORCEPROP 2 LAST PATH I33
J 0
(5975 -2700);
DISPLAY 1.021277 (5975 -2700);
DISPLAY INVISIBLE (5975 -2700);
FORCEADD OFFPAGE..2
(5775 -2125);
FORCEPROP 2 LAST $XR0 214 
J 0
(5964 -2125);
DISPLAY 0.638298 (5964 -2125);
PAINT MONO (5964 -2125);
FORCEPROP 2 LAST CDS_LIB standard
J 0
(5775 -2125);
DISPLAY INVISIBLE (5775 -2125);
FORCEPROP 1 LAST OFFPAGE TRUE
J 0
(6100 -2250);
DISPLAY 0.872340 (6100 -2250);
PAINT GREEN (6100 -2250);
DISPLAY INVISIBLE (6100 -2250);
FORCEPROP 1 LAST COMMENT_BODY TRUE
J 0
(5730 -2220);
DISPLAY 0.872340 (5730 -2220);
PAINT GREEN (5730 -2220);
DISPLAY INVISIBLE (5730 -2220);
FORCEPROP 2 LAST PATH I34
J 0
(5975 -2075);
DISPLAY 1.021277 (5975 -2075);
DISPLAY INVISIBLE (5975 -2075);
FORCEADD OFFPAGE..2
(5775 -1500);
FORCEPROP 2 LAST $XR0 214 
J 0
(5964 -1500);
DISPLAY 0.638298 (5964 -1500);
PAINT MONO (5964 -1500);
FORCEPROP 1 LAST COMMENT_BODY TRUE
J 0
(5730 -1595);
DISPLAY 0.872340 (5730 -1595);
PAINT GREEN (5730 -1595);
DISPLAY INVISIBLE (5730 -1595);
FORCEPROP 1 LAST OFFPAGE TRUE
J 0
(6100 -1625);
DISPLAY 0.872340 (6100 -1625);
PAINT GREEN (6100 -1625);
DISPLAY INVISIBLE (6100 -1625);
FORCEPROP 2 LAST CDS_LIB standard
J 0
(5775 -1500);
DISPLAY INVISIBLE (5775 -1500);
FORCEPROP 2 LAST PATH I35
J 0
(5975 -1450);
DISPLAY 1.021277 (5975 -1450);
DISPLAY INVISIBLE (5975 -1450);
FORCEADD OFFPAGE..2
(5775 -875);
FORCEPROP 2 LAST $XR0 214 
J 0
(5964 -875);
DISPLAY 0.638298 (5964 -875);
PAINT MONO (5964 -875);
FORCEPROP 2 LAST CDS_LIB standard
J 0
(5775 -875);
DISPLAY INVISIBLE (5775 -875);
FORCEPROP 1 LAST OFFPAGE TRUE
J 0
(6100 -1000);
DISPLAY 0.872340 (6100 -1000);
PAINT GREEN (6100 -1000);
DISPLAY INVISIBLE (6100 -1000);
FORCEPROP 1 LAST COMMENT_BODY TRUE
J 0
(5730 -970);
DISPLAY 0.872340 (5730 -970);
PAINT GREEN (5730 -970);
DISPLAY INVISIBLE (5730 -970);
FORCEPROP 2 LAST PATH I36
J 0
(5975 -825);
DISPLAY 1.021277 (5975 -825);
DISPLAY INVISIBLE (5975 -825);
FORCEADD Q_RES..1
(1825 350);
FORCEPROP 1 LAST PART_NUMBER CS31002FB08
J 0
(1925 275);
DISPLAY 0.638298 (1925 275);
DISPLAY INVISIBLE (1925 275);
FORCEPROP 1 LAST WATTAGE 1/16W
J 2
(1800 225);
DISPLAY 0.638298 (1800 225);
FORCEPROP 1 LAST PACK_TYPE 0402LF
J 0
(2075 225);
DISPLAY 0.638298 (2075 225);
FORCEPROP 1 LAST VALUE 10K
J 2
(1800 275);
DISPLAY 0.638298 (1800 275);
FORCEPROP 1 LAST TOLERANCE 1%
J 0
(1825 275);
DISPLAY 0.638298 (1825 275);
FORCEPROP 1 LAST MATERIAL CHIP
J 0
(1825 225);
DISPLAY 0.638298 (1825 225);
FORCEPROP 1 LAST $LOCATION R943
J 0
(1600 350);
DISPLAY 0.787234 (1600 350);
FORCEPROP 1 LASTPIN (1725 350) $PN 1
J 0
(1737 362);
DISPLAY 0.787234 (1737 362);
PAINT MONO (1737 362);
FORCEPROP 1 LASTPIN (1925 350) $PN 2
J 0
(1887 362);
DISPLAY 0.787234 (1887 362);
PAINT MONO (1887 362);
FORCEPROP 1 LAST PATH I37
J 0
(1775 500);
DISPLAY 0.978723 (1775 500);
PAINT WHITE (1775 500);
DISPLAY INVISIBLE (1775 500);
FORCEPROP 2 LAST CDS_LIB pure_quanta
J 0
(1825 350);
DISPLAY INVISIBLE (1825 350);
FORCEPROP 2 LAST CDS_LOCATION R943
J 0
(1775 550);
DISPLAY 1.021277 (1775 550);
DISPLAY INVISIBLE (1775 550);
FORCEPROP 0 LAST $SEC 1
J 0
(1600 400);
DISPLAY 0.680851 (1600 400);
PAINT MONO (1600 400);
DISPLAY INVISIBLE (1600 400);
FORCEPROP 2 LAST CDS_SEC 1
J 0
(1775 550);
DISPLAY 1.021277 (1775 550);
DISPLAY INVISIBLE (1775 550);
FORCEADD Q_RES..1
(1825 100);
FORCEPROP 1 LAST PART_NUMBER CS21002FB06
J 0
(1925 25);
DISPLAY 0.638298 (1925 25);
DISPLAY INVISIBLE (1925 25);
FORCEPROP 1 LAST PACK_TYPE 0402LF
J 0
(2075 -25);
DISPLAY 0.638298 (2075 -25);
FORCEPROP 1 LAST WATTAGE 1/16W
J 2
(1800 -25);
DISPLAY 0.638298 (1800 -25);
FORCEPROP 1 LAST VALUE 1K
J 2
(1800 25);
DISPLAY 0.638298 (1800 25);
FORCEPROP 1 LAST TOLERANCE 1%
J 0
(1825 25);
DISPLAY 0.638298 (1825 25);
FORCEPROP 1 LAST MATERIAL CHIP
J 0
(1825 -25);
DISPLAY 0.638298 (1825 -25);
FORCEPROP 1 LAST $LOCATION R2493
J 0
(1575 100);
DISPLAY 0.787234 (1575 100);
FORCEPROP 1 LASTPIN (1725 100) $PN 1
J 0
(1737 112);
DISPLAY 0.787234 (1737 112);
PAINT MONO (1737 112);
FORCEPROP 1 LASTPIN (1925 100) $PN 2
J 0
(1887 112);
DISPLAY 0.787234 (1887 112);
PAINT MONO (1887 112);
FORCEPROP 1 LAST PATH I38
J 0
(1775 250);
DISPLAY 0.978723 (1775 250);
PAINT WHITE (1775 250);
DISPLAY INVISIBLE (1775 250);
FORCEPROP 2 LAST CDS_LIB pure_quanta
J 0
(1825 100);
DISPLAY INVISIBLE (1825 100);
FORCEPROP 0 LAST CDS_LOCATION R2493
J 0
(2000 250);
DISPLAY 1.021277 (2000 250);
DISPLAY INVISIBLE (2000 250);
FORCEPROP 0 LAST $SEC 1
J 0
(1575 150);
DISPLAY 0.680851 (1575 150);
PAINT MONO (1575 150);
DISPLAY INVISIBLE (1575 150);
FORCEPROP 0 LAST CDS_SEC 1
J 0
(2000 250);
DISPLAY 1.021277 (2000 250);
DISPLAY INVISIBLE (2000 250);
FORCEADD UNIVERSAL_POWER..1
(1400 525);
FORCEPROP 3 LASTPIN (1400 475) SIG_NAME P3V3_AUX\g
J 0
(1410 485);
DISPLAY 0.659574 (1410 485);
PAINT MONO (1410 485);
DISPLAY INVISIBLE (1410 485);
FORCEPROP 1 LAST HDL_POWER P3V3_AUX
J 1
(1400 575);
DISPLAY 0.872340 (1400 575);
PAINT GREEN (1400 575);
FORCEPROP 2 LAST CDS_LIB logical_power
J 0
(1400 525);
DISPLAY INVISIBLE (1400 525);
FORCEPROP 1 LAST PATH I39
J 0
(1450 550);
DISPLAY 0.872340 (1450 550);
PAINT AQUA (1450 550);
DISPLAY INVISIBLE (1450 550);
FORCEADD OFFPAGE..1
(525 -875);
FORCEPROP 2 LAST $XR0 114 
J 0
(273 -875);
DISPLAY 0.638298 (273 -875);
PAINT MONO (273 -875);
FORCEPROP 2 LAST CDS_LIB standard
J 0
(525 -875);
PAINT MONO (525 -875);
DISPLAY INVISIBLE (525 -875);
FORCEPROP 1 LAST OFFPAGE TRUE
J 0
(850 -1000);
DISPLAY 0.872340 (850 -1000);
PAINT GREEN (850 -1000);
DISPLAY INVISIBLE (850 -1000);
FORCEPROP 1 LAST COMMENT_BODY TRUE
J 0
(650 -975);
DISPLAY 0.872340 (650 -975);
PAINT GREEN (650 -975);
DISPLAY INVISIBLE (650 -975);
FORCEPROP 2 LAST PATH I4
J 0
(250 -825);
DISPLAY 1.021277 (250 -825);
DISPLAY INVISIBLE (250 -825);
FORCEADD Q_RES..1
(1825 975);
FORCEPROP 1 LAST PART_NUMBER CS31002FB08
J 0
(1925 900);
DISPLAY 0.638298 (1925 900);
DISPLAY INVISIBLE (1925 900);
FORCEPROP 1 LAST TOLERANCE 1%
J 0
(1825 900);
DISPLAY 0.638298 (1825 900);
FORCEPROP 1 LAST WATTAGE 1/16W
J 2
(1800 850);
DISPLAY 0.638298 (1800 850);
FORCEPROP 1 LAST PACK_TYPE 0402LF
J 0
(2075 850);
DISPLAY 0.638298 (2075 850);
FORCEPROP 1 LAST MATERIAL CHIP
J 0
(1825 850);
DISPLAY 0.638298 (1825 850);
FORCEPROP 1 LAST VALUE 10K
J 2
(1800 900);
DISPLAY 0.638298 (1800 900);
FORCEPROP 1 LAST $LOCATION R942
J 0
(1600 975);
DISPLAY 0.787234 (1600 975);
FORCEPROP 1 LASTPIN (1725 975) $PN 1
J 0
(1737 987);
DISPLAY 0.787234 (1737 987);
PAINT MONO (1737 987);
FORCEPROP 1 LASTPIN (1925 975) $PN 2
J 0
(1887 987);
DISPLAY 0.787234 (1887 987);
PAINT MONO (1887 987);
FORCEPROP 1 LAST PATH I40
J 0
(1775 1125);
DISPLAY 0.978723 (1775 1125);
PAINT WHITE (1775 1125);
DISPLAY INVISIBLE (1775 1125);
FORCEPROP 2 LAST CDS_LIB pure_quanta
J 0
(1825 975);
DISPLAY INVISIBLE (1825 975);
FORCEPROP 2 LAST CDS_LOCATION R942
J 0
(1775 1175);
DISPLAY 1.021277 (1775 1175);
DISPLAY INVISIBLE (1775 1175);
FORCEPROP 0 LAST $SEC 1
J 0
(1600 1025);
DISPLAY 0.680851 (1600 1025);
PAINT MONO (1600 1025);
DISPLAY INVISIBLE (1600 1025);
FORCEPROP 2 LAST CDS_SEC 1
J 0
(1775 1175);
DISPLAY 1.021277 (1775 1175);
DISPLAY INVISIBLE (1775 1175);
FORCEADD Q_RES..1
(1825 725);
FORCEPROP 1 LAST PART_NUMBER CS21002FB06
J 0
(1950 675);
DISPLAY 0.638298 (1950 675);
DISPLAY INVISIBLE (1950 675);
FORCEPROP 1 LAST WATTAGE 1/16W
J 2
(1825 625);
DISPLAY 0.638298 (1825 625);
FORCEPROP 1 LAST PACK_TYPE 0402LF
J 0
(2100 625);
DISPLAY 0.638298 (2100 625);
FORCEPROP 1 LAST TOLERANCE 1%
J 0
(1850 675);
DISPLAY 0.638298 (1850 675);
FORCEPROP 1 LAST VALUE 1K
J 2
(1825 675);
DISPLAY 0.638298 (1825 675);
FORCEPROP 1 LAST MATERIAL CHIP
J 0
(1850 625);
DISPLAY 0.638298 (1850 625);
FORCEPROP 1 LAST $LOCATION R2492
J 0
(1600 725);
DISPLAY 0.787234 (1600 725);
FORCEPROP 1 LASTPIN (1725 725) $PN 1
J 0
(1737 737);
DISPLAY 0.787234 (1737 737);
PAINT MONO (1737 737);
FORCEPROP 1 LASTPIN (1925 725) $PN 2
J 0
(1887 737);
DISPLAY 0.787234 (1887 737);
PAINT MONO (1887 737);
FORCEPROP 1 LAST PATH I41
J 0
(1775 875);
DISPLAY 0.978723 (1775 875);
PAINT WHITE (1775 875);
DISPLAY INVISIBLE (1775 875);
FORCEPROP 2 LAST CDS_LIB pure_quanta
J 0
(1825 725);
DISPLAY INVISIBLE (1825 725);
FORCEPROP 0 LAST CDS_LOCATION R2492
J 0
(2000 875);
DISPLAY 1.021277 (2000 875);
DISPLAY INVISIBLE (2000 875);
FORCEPROP 0 LAST $SEC 1
J 0
(1600 775);
DISPLAY 0.680851 (1600 775);
PAINT MONO (1600 775);
DISPLAY INVISIBLE (1600 775);
FORCEPROP 0 LAST CDS_SEC 1
J 0
(2000 875);
DISPLAY 1.021277 (2000 875);
DISPLAY INVISIBLE (2000 875);
FORCEADD Q_RES..1
(1825 1350);
FORCEPROP 1 LAST PART_NUMBER CS21002FB06
J 0
(1925 1300);
DISPLAY 0.638298 (1925 1300);
DISPLAY INVISIBLE (1925 1300);
FORCEPROP 1 LAST VALUE 1K
J 2
(1800 1300);
DISPLAY 0.638298 (1800 1300);
FORCEPROP 1 LAST TOLERANCE 1%
J 0
(1825 1300);
DISPLAY 0.638298 (1825 1300);
FORCEPROP 1 LAST PACK_TYPE 0402LF
J 0
(2075 1250);
DISPLAY 0.638298 (2075 1250);
FORCEPROP 1 LAST WATTAGE 1/16W
J 2
(1800 1250);
DISPLAY 0.638298 (1800 1250);
FORCEPROP 1 LAST MATERIAL CHIP
J 0
(1825 1250);
DISPLAY 0.638298 (1825 1250);
FORCEPROP 1 LAST $LOCATION R2491
J 0
(1575 1350);
DISPLAY 0.787234 (1575 1350);
FORCEPROP 1 LASTPIN (1725 1350) $PN 1
J 0
(1737 1362);
DISPLAY 0.787234 (1737 1362);
PAINT MONO (1737 1362);
FORCEPROP 1 LASTPIN (1925 1350) $PN 2
J 0
(1887 1362);
DISPLAY 0.787234 (1887 1362);
PAINT MONO (1887 1362);
FORCEPROP 1 LAST PATH I42
J 0
(1775 1500);
DISPLAY 0.978723 (1775 1500);
PAINT WHITE (1775 1500);
DISPLAY INVISIBLE (1775 1500);
FORCEPROP 2 LAST CDS_LIB pure_quanta
J 0
(1825 1350);
DISPLAY INVISIBLE (1825 1350);
FORCEPROP 0 LAST CDS_LOCATION R2491
J 0
(2000 1500);
DISPLAY 1.021277 (2000 1500);
DISPLAY INVISIBLE (2000 1500);
FORCEPROP 0 LAST $SEC 1
J 0
(1575 1400);
DISPLAY 0.680851 (1575 1400);
PAINT MONO (1575 1400);
DISPLAY INVISIBLE (1575 1400);
FORCEPROP 0 LAST CDS_SEC 1
J 0
(2000 1500);
DISPLAY 1.021277 (2000 1500);
DISPLAY INVISIBLE (2000 1500);
FORCEADD UNIVERSAL_POWER..1
(1400 1150);
FORCEPROP 3 LASTPIN (1400 1100) SIG_NAME P3V3_AUX\g
J 0
(1410 1110);
DISPLAY 0.659574 (1410 1110);
PAINT MONO (1410 1110);
DISPLAY INVISIBLE (1410 1110);
FORCEPROP 1 LAST HDL_POWER P3V3_AUX
J 1
(1400 1200);
DISPLAY 0.872340 (1400 1200);
PAINT GREEN (1400 1200);
FORCEPROP 2 LAST CDS_LIB logical_power
J 0
(1400 1150);
DISPLAY INVISIBLE (1400 1150);
FORCEPROP 1 LAST PATH I43
J 0
(1450 1175);
DISPLAY 0.872340 (1450 1175);
PAINT AQUA (1450 1175);
DISPLAY INVISIBLE (1450 1175);
FORCEADD UNIVERSAL_POWER..1
(1400 1775);
FORCEPROP 3 LASTPIN (1400 1725) SIG_NAME P3V3_AUX\g
J 0
(1410 1735);
DISPLAY 0.659574 (1410 1735);
PAINT MONO (1410 1735);
DISPLAY INVISIBLE (1410 1735);
FORCEPROP 1 LAST HDL_POWER P3V3_AUX
J 1
(1400 1825);
DISPLAY 0.872340 (1400 1825);
PAINT GREEN (1400 1825);
FORCEPROP 2 LAST CDS_LIB logical_power
J 0
(1400 1775);
DISPLAY INVISIBLE (1400 1775);
FORCEPROP 1 LAST PATH I44
J 0
(1450 1800);
DISPLAY 0.872340 (1450 1800);
PAINT AQUA (1450 1800);
DISPLAY INVISIBLE (1450 1800);
FORCEADD Q_RES..1
(1825 1600);
FORCEPROP 1 LAST PART_NUMBER CS31002FB08
J 0
(1925 1550);
DISPLAY 0.638298 (1925 1550);
DISPLAY INVISIBLE (1925 1550);
FORCEPROP 1 LAST VALUE 10K
J 2
(1800 1550);
DISPLAY 0.638298 (1800 1550);
FORCEPROP 1 LAST TOLERANCE 1%
J 0
(1825 1550);
DISPLAY 0.638298 (1825 1550);
FORCEPROP 1 LAST MATERIAL CHIP
J 0
(1825 1500);
DISPLAY 0.638298 (1825 1500);
FORCEPROP 1 LAST WATTAGE 1/16W
J 2
(1800 1500);
DISPLAY 0.638298 (1800 1500);
FORCEPROP 1 LAST PACK_TYPE 0402LF
J 0
(2075 1500);
DISPLAY 0.638298 (2075 1500);
FORCEPROP 1 LAST $LOCATION R941
J 0
(1575 1600);
DISPLAY 0.978723 (1575 1600);
FORCEPROP 1 LASTPIN (1725 1600) $PN 1
J 0
(1737 1612);
DISPLAY 0.787234 (1737 1612);
PAINT MONO (1737 1612);
FORCEPROP 1 LASTPIN (1925 1600) $PN 2
J 0
(1887 1612);
DISPLAY 0.787234 (1887 1612);
PAINT MONO (1887 1612);
FORCEPROP 1 LAST PATH I45
J 0
(1775 1750);
DISPLAY 0.978723 (1775 1750);
PAINT WHITE (1775 1750);
DISPLAY INVISIBLE (1775 1750);
FORCEPROP 2 LAST CDS_LIB pure_quanta
J 0
(1825 1600);
DISPLAY INVISIBLE (1825 1600);
FORCEPROP 2 LAST CDS_LOCATION R941
J 0
(1775 1800);
DISPLAY 1.021277 (1775 1800);
DISPLAY INVISIBLE (1775 1800);
FORCEPROP 0 LAST $SEC 1
J 0
(1575 1650);
DISPLAY 0.680851 (1575 1650);
PAINT MONO (1575 1650);
DISPLAY INVISIBLE (1575 1650);
FORCEPROP 2 LAST CDS_SEC 1
J 0
(1775 1800);
DISPLAY 1.021277 (1775 1800);
DISPLAY INVISIBLE (1775 1800);
FORCEADD Q_RES..1
(1825 1975);
FORCEPROP 1 LAST PART_NUMBER CS21002FB06
J 0
(1925 1925);
DISPLAY 0.638298 (1925 1925);
DISPLAY INVISIBLE (1925 1925);
FORCEPROP 1 LAST WATTAGE 1/16W
J 2
(1800 1875);
DISPLAY 0.638298 (1800 1875);
FORCEPROP 1 LAST MATERIAL CHIP
J 0
(1825 1875);
DISPLAY 0.638298 (1825 1875);
FORCEPROP 1 LAST VALUE 1K
J 2
(1800 1925);
DISPLAY 0.638298 (1800 1925);
FORCEPROP 1 LAST TOLERANCE 1%
J 0
(1825 1925);
DISPLAY 0.638298 (1825 1925);
FORCEPROP 1 LAST PACK_TYPE 0402LF
J 0
(2075 1875);
DISPLAY 0.638298 (2075 1875);
FORCEPROP 1 LAST $LOCATION R2490
J 0
(1575 1975);
DISPLAY 0.787234 (1575 1975);
FORCEPROP 1 LASTPIN (1725 1975) $PN 1
J 0
(1737 1987);
DISPLAY 0.787234 (1737 1987);
PAINT MONO (1737 1987);
FORCEPROP 1 LASTPIN (1925 1975) $PN 2
J 0
(1887 1987);
DISPLAY 0.787234 (1887 1987);
PAINT MONO (1887 1987);
FORCEPROP 1 LAST PATH I46
J 0
(1775 2125);
DISPLAY 0.978723 (1775 2125);
PAINT WHITE (1775 2125);
DISPLAY INVISIBLE (1775 2125);
FORCEPROP 2 LAST CDS_LIB pure_quanta
J 0
(1825 1975);
DISPLAY INVISIBLE (1825 1975);
FORCEPROP 0 LAST CDS_LOCATION R2490
J 0
(2000 2125);
DISPLAY 1.021277 (2000 2125);
DISPLAY INVISIBLE (2000 2125);
FORCEPROP 0 LAST $SEC 1
J 0
(1575 2025);
DISPLAY 0.680851 (1575 2025);
PAINT MONO (1575 2025);
DISPLAY INVISIBLE (1575 2025);
FORCEPROP 0 LAST CDS_SEC 1
J 0
(2000 2125);
DISPLAY 1.021277 (2000 2125);
DISPLAY INVISIBLE (2000 2125);
FORCEADD UNIVERSAL_POWER..1
(1400 2400);
FORCEPROP 3 LASTPIN (1400 2350) SIG_NAME P3V3_AUX\g
J 0
(1410 2360);
DISPLAY 0.659574 (1410 2360);
PAINT MONO (1410 2360);
DISPLAY INVISIBLE (1410 2360);
FORCEPROP 1 LAST HDL_POWER P3V3_AUX
J 1
(1400 2450);
DISPLAY 0.872340 (1400 2450);
PAINT GREEN (1400 2450);
FORCEPROP 2 LAST CDS_LIB logical_power
J 0
(1400 2400);
DISPLAY INVISIBLE (1400 2400);
FORCEPROP 1 LAST PATH I47
J 0
(1450 2425);
DISPLAY 0.872340 (1450 2425);
PAINT AQUA (1450 2425);
DISPLAY INVISIBLE (1450 2425);
FORCEADD Q_RES..1
(1825 2225);
FORCEPROP 1 LAST PART_NUMBER CS31002FB08
J 0
(1925 2175);
DISPLAY 0.638298 (1925 2175);
DISPLAY INVISIBLE (1925 2175);
FORCEPROP 1 LAST VALUE 10K
J 2
(1800 2175);
DISPLAY 0.638298 (1800 2175);
FORCEPROP 1 LAST TOLERANCE 1%
J 0
(1825 2175);
DISPLAY 0.638298 (1825 2175);
FORCEPROP 1 LAST PACK_TYPE 0402LF
J 0
(2075 2125);
DISPLAY 0.638298 (2075 2125);
FORCEPROP 1 LAST WATTAGE 1/16W
J 2
(1800 2125);
DISPLAY 0.638298 (1800 2125);
FORCEPROP 1 LAST MATERIAL CHIP
J 0
(1825 2125);
DISPLAY 0.638298 (1825 2125);
FORCEPROP 1 LAST $LOCATION R940
J 0
(1575 2225);
DISPLAY 0.787234 (1575 2225);
FORCEPROP 1 LASTPIN (1725 2225) $PN 1
J 0
(1737 2237);
DISPLAY 0.787234 (1737 2237);
PAINT MONO (1737 2237);
FORCEPROP 1 LASTPIN (1925 2225) $PN 2
J 0
(1887 2237);
DISPLAY 0.787234 (1887 2237);
PAINT MONO (1887 2237);
FORCEPROP 1 LAST PATH I48
J 0
(1775 2375);
DISPLAY 0.978723 (1775 2375);
PAINT WHITE (1775 2375);
DISPLAY INVISIBLE (1775 2375);
FORCEPROP 2 LAST CDS_LIB pure_quanta
J 0
(1825 2225);
DISPLAY INVISIBLE (1825 2225);
FORCEPROP 2 LAST CDS_LOCATION R940
J 0
(1775 2425);
DISPLAY 1.021277 (1775 2425);
DISPLAY INVISIBLE (1775 2425);
FORCEPROP 0 LAST $SEC 1
J 0
(1575 2275);
DISPLAY 0.680851 (1575 2275);
PAINT MONO (1575 2275);
DISPLAY INVISIBLE (1575 2275);
FORCEPROP 2 LAST CDS_SEC 1
J 0
(1775 2425);
DISPLAY 1.021277 (1775 2425);
DISPLAY INVISIBLE (1775 2425);
FORCEADD OFFPAGE..1
(525 100);
FORCEPROP 2 LAST $XR0 114 
J 0
(273 100);
DISPLAY 0.638298 (273 100);
PAINT MONO (273 100);
FORCEPROP 2 LAST CDS_LIB standard
J 0
(525 100);
PAINT MONO (525 100);
DISPLAY INVISIBLE (525 100);
FORCEPROP 1 LAST OFFPAGE TRUE
J 0
(850 -25);
DISPLAY 0.872340 (850 -25);
PAINT GREEN (850 -25);
DISPLAY INVISIBLE (850 -25);
FORCEPROP 1 LAST COMMENT_BODY TRUE
J 0
(650 0);
DISPLAY 0.872340 (650 0);
PAINT GREEN (650 0);
DISPLAY INVISIBLE (650 0);
FORCEPROP 2 LAST PATH I5
J 0
(250 150);
DISPLAY 1.021277 (250 150);
DISPLAY INVISIBLE (250 150);
FORCEADD SCHOTTKY_12..1
(4100 350);
FORCEPROP 1 LAST PART_NUMBER BC000530Z41
J 0
(4025 475);
DISPLAY 0.574468 (4025 475);
PAINT GREEN (4025 475);
DISPLAY INVISIBLE (4025 475);
FORCEPROP 2 LAST VALUE B0530WS7F
J 0
(4025 575);
DISPLAY 0.808511 (4025 575);
FORCEPROP 2 LAST PART_TYPE SMLF
J 0
(4025 625);
DISPLAY 0.808511 (4025 625);
FORCEPROP 1 LAST MATERIAL IC
J 0
(4025 425);
DISPLAY 0.574468 (4025 425);
PAINT GREEN (4025 425);
FORCEPROP 1 LAST $LOCATION D45
J 0
(4025 525);
DISPLAY 0.574468 (4025 525);
PAINT GREEN (4025 525);
FORCEPROP 0 LASTPIN (3975 350) $PN 1
J 2
(3965 360);
DISPLAY 0.680851 (3965 360);
PAINT MONO (3965 360);
FORCEPROP 0 LASTPIN (4225 350) $PN 2
J 0
(4235 360);
DISPLAY 0.680851 (4235 360);
PAINT MONO (4235 360);
FORCEPROP 2 LAST CDS_LIB pure_quanta
J 0
(4100 350);
DISPLAY INVISIBLE (4100 350);
FORCEPROP 1 LAST NEEDS_NO_SIZE TRUE
J 0
(4175 300);
DISPLAY 0.468085 (4175 300);
PAINT GREEN (4175 300);
DISPLAY INVISIBLE (4175 300);
FORCEPROP 1 LAST CDS_LMAN_SYM_OUTLINE -75,50,75,-50
J 0
(4100 350);
DISPLAY 0.468085 (4100 350);
PAINT GREEN (4100 350);
DISPLAY INVISIBLE (4100 350);
FORCEPROP 1 LAST PATH I50
J 0
(4100 350);
DISPLAY 0.723404 (4100 350);
PAINT GREEN (4100 350);
DISPLAY INVISIBLE (4100 350);
FORCEPROP 0 LAST CDS_LOCATION D45
J 0
(4025 675);
DISPLAY 1.021277 (4025 675);
DISPLAY INVISIBLE (4025 675);
FORCEPROP 0 LAST $SEC 1
J 0
(4025 675);
DISPLAY 0.680851 (4025 675);
PAINT MONO (4025 675);
DISPLAY INVISIBLE (4025 675);
FORCEPROP 0 LAST CDS_SEC 1
J 0
(4025 675);
DISPLAY 1.021277 (4025 675);
DISPLAY INVISIBLE (4025 675);
FORCEADD SCHOTTKY_12..1
(4100 975);
FORCEPROP 1 LAST PART_NUMBER BC000530Z41
J 0
(4025 1100);
DISPLAY 0.574468 (4025 1100);
PAINT GREEN (4025 1100);
DISPLAY INVISIBLE (4025 1100);
FORCEPROP 2 LAST PART_TYPE SMLF
J 0
(4025 1250);
DISPLAY 0.808511 (4025 1250);
FORCEPROP 2 LAST VALUE B0530WS7F
J 0
(4025 1200);
DISPLAY 0.808511 (4025 1200);
FORCEPROP 1 LAST MATERIAL IC
J 0
(4025 1050);
DISPLAY 0.574468 (4025 1050);
PAINT GREEN (4025 1050);
FORCEPROP 1 LAST $LOCATION D44
J 0
(4025 1150);
DISPLAY 0.574468 (4025 1150);
PAINT GREEN (4025 1150);
FORCEPROP 0 LASTPIN (3975 975) $PN 1
J 2
(3965 985);
DISPLAY 0.680851 (3965 985);
PAINT MONO (3965 985);
FORCEPROP 0 LASTPIN (4225 975) $PN 2
J 0
(4235 985);
DISPLAY 0.680851 (4235 985);
PAINT MONO (4235 985);
FORCEPROP 1 LAST CDS_LMAN_SYM_OUTLINE -75,50,75,-50
J 0
(4100 975);
DISPLAY 0.468085 (4100 975);
PAINT GREEN (4100 975);
DISPLAY INVISIBLE (4100 975);
FORCEPROP 1 LAST NEEDS_NO_SIZE TRUE
J 0
(4175 925);
DISPLAY 0.468085 (4175 925);
PAINT GREEN (4175 925);
DISPLAY INVISIBLE (4175 925);
FORCEPROP 2 LAST CDS_LIB pure_quanta
J 0
(4100 975);
DISPLAY INVISIBLE (4100 975);
FORCEPROP 1 LAST PATH I52
J 0
(4100 975);
DISPLAY 0.723404 (4100 975);
PAINT GREEN (4100 975);
DISPLAY INVISIBLE (4100 975);
FORCEPROP 0 LAST CDS_LOCATION D44
J 0
(4025 1300);
DISPLAY 1.021277 (4025 1300);
DISPLAY INVISIBLE (4025 1300);
FORCEPROP 0 LAST $SEC 1
J 0
(4025 1300);
DISPLAY 0.680851 (4025 1300);
PAINT MONO (4025 1300);
DISPLAY INVISIBLE (4025 1300);
FORCEPROP 0 LAST CDS_SEC 1
J 0
(4025 1300);
DISPLAY 1.021277 (4025 1300);
DISPLAY INVISIBLE (4025 1300);
FORCEADD SCHOTTKY_12..1
(4100 1600);
FORCEPROP 1 LAST PART_NUMBER BC000530Z41
J 0
(4025 1725);
DISPLAY 0.574468 (4025 1725);
PAINT GREEN (4025 1725);
DISPLAY INVISIBLE (4025 1725);
FORCEPROP 2 LAST VALUE B0530WS7F
J 0
(4025 1825);
DISPLAY 0.808511 (4025 1825);
FORCEPROP 2 LAST PART_TYPE SMLF
J 0
(4025 1875);
DISPLAY 0.808511 (4025 1875);
FORCEPROP 1 LAST MATERIAL IC
J 0
(4025 1675);
DISPLAY 0.574468 (4025 1675);
PAINT GREEN (4025 1675);
FORCEPROP 1 LAST $LOCATION D43
J 0
(4025 1775);
DISPLAY 0.574468 (4025 1775);
PAINT GREEN (4025 1775);
FORCEPROP 0 LASTPIN (3975 1600) $PN 1
J 2
(3965 1610);
DISPLAY 0.680851 (3965 1610);
PAINT MONO (3965 1610);
FORCEPROP 0 LASTPIN (4225 1600) $PN 2
J 0
(4235 1610);
DISPLAY 0.680851 (4235 1610);
PAINT MONO (4235 1610);
FORCEPROP 2 LAST CDS_LIB pure_quanta
J 0
(4100 1600);
DISPLAY INVISIBLE (4100 1600);
FORCEPROP 1 LAST NEEDS_NO_SIZE TRUE
J 0
(4175 1550);
DISPLAY 0.468085 (4175 1550);
PAINT GREEN (4175 1550);
DISPLAY INVISIBLE (4175 1550);
FORCEPROP 1 LAST CDS_LMAN_SYM_OUTLINE -75,50,75,-50
J 0
(4100 1600);
DISPLAY 0.468085 (4100 1600);
PAINT GREEN (4100 1600);
DISPLAY INVISIBLE (4100 1600);
FORCEPROP 1 LAST PATH I54
J 0
(4100 1600);
DISPLAY 0.723404 (4100 1600);
PAINT GREEN (4100 1600);
DISPLAY INVISIBLE (4100 1600);
FORCEPROP 0 LAST CDS_LOCATION D43
J 0
(4025 1925);
DISPLAY 1.021277 (4025 1925);
DISPLAY INVISIBLE (4025 1925);
FORCEPROP 0 LAST $SEC 1
J 0
(4025 1925);
DISPLAY 0.680851 (4025 1925);
PAINT MONO (4025 1925);
DISPLAY INVISIBLE (4025 1925);
FORCEPROP 0 LAST CDS_SEC 1
J 0
(4025 1925);
DISPLAY 1.021277 (4025 1925);
DISPLAY INVISIBLE (4025 1925);
FORCEADD UNIVERSAL_POWER..1
(4725 525);
FORCEPROP 3 LASTPIN (4725 475) SIG_NAME P3V3_AUX\g
J 0
(4735 485);
DISPLAY 0.659574 (4735 485);
PAINT MONO (4735 485);
DISPLAY INVISIBLE (4735 485);
FORCEPROP 1 LAST HDL_POWER P3V3_AUX
J 1
(4725 575);
DISPLAY 0.872340 (4725 575);
PAINT GREEN (4725 575);
FORCEPROP 2 LAST CDS_LIB logical_power
J 0
(4725 525);
DISPLAY INVISIBLE (4725 525);
FORCEPROP 1 LAST PATH I56
J 0
(4775 550);
DISPLAY 0.872340 (4775 550);
PAINT AQUA (4775 550);
DISPLAY INVISIBLE (4775 550);
FORCEADD UNIVERSAL_POWER..1
(4725 1150);
FORCEPROP 3 LASTPIN (4725 1100) SIG_NAME P3V3_AUX\g
J 0
(4735 1110);
DISPLAY 0.659574 (4735 1110);
PAINT MONO (4735 1110);
DISPLAY INVISIBLE (4735 1110);
FORCEPROP 1 LAST HDL_POWER P3V3_AUX
J 1
(4725 1200);
DISPLAY 0.872340 (4725 1200);
PAINT GREEN (4725 1200);
FORCEPROP 2 LAST CDS_LIB logical_power
J 0
(4725 1150);
DISPLAY INVISIBLE (4725 1150);
FORCEPROP 1 LAST PATH I57
J 0
(4775 1175);
DISPLAY 0.872340 (4775 1175);
PAINT AQUA (4775 1175);
DISPLAY INVISIBLE (4775 1175);
FORCEADD UNIVERSAL_POWER..1
(4725 1775);
FORCEPROP 3 LASTPIN (4725 1725) SIG_NAME P3V3_AUX\g
J 0
(4735 1735);
DISPLAY 0.659574 (4735 1735);
PAINT MONO (4735 1735);
DISPLAY INVISIBLE (4735 1735);
FORCEPROP 1 LAST HDL_POWER P3V3_AUX
J 1
(4725 1825);
DISPLAY 0.872340 (4725 1825);
PAINT GREEN (4725 1825);
FORCEPROP 2 LAST CDS_LIB logical_power
J 0
(4725 1775);
DISPLAY INVISIBLE (4725 1775);
FORCEPROP 1 LAST PATH I58
J 0
(4775 1800);
DISPLAY 0.872340 (4775 1800);
PAINT AQUA (4775 1800);
DISPLAY INVISIBLE (4775 1800);
FORCEADD SCHOTTKY_12..1
(4100 2225);
FORCEPROP 1 LAST PART_NUMBER BC000530Z41
J 0
(4025 2350);
DISPLAY 0.574468 (4025 2350);
PAINT GREEN (4025 2350);
DISPLAY INVISIBLE (4025 2350);
FORCEPROP 2 LAST PART_TYPE SMLF
J 0
(4025 2500);
DISPLAY 0.808511 (4025 2500);
FORCEPROP 2 LAST VALUE B0530WS7F
J 0
(4025 2450);
DISPLAY 0.808511 (4025 2450);
FORCEPROP 1 LAST MATERIAL IC
J 0
(4025 2300);
DISPLAY 0.574468 (4025 2300);
PAINT GREEN (4025 2300);
FORCEPROP 1 LAST $LOCATION D42
J 0
(4025 2400);
DISPLAY 0.574468 (4025 2400);
PAINT GREEN (4025 2400);
FORCEPROP 0 LASTPIN (3975 2225) $PN 1
J 2
(3965 2235);
DISPLAY 0.680851 (3965 2235);
PAINT MONO (3965 2235);
FORCEPROP 0 LASTPIN (4225 2225) $PN 2
J 0
(4235 2235);
DISPLAY 0.680851 (4235 2235);
PAINT MONO (4235 2235);
FORCEPROP 1 LAST CDS_LMAN_SYM_OUTLINE -75,50,75,-50
J 0
(4100 2225);
DISPLAY 0.468085 (4100 2225);
PAINT GREEN (4100 2225);
DISPLAY INVISIBLE (4100 2225);
FORCEPROP 1 LAST NEEDS_NO_SIZE TRUE
J 0
(4175 2175);
DISPLAY 0.468085 (4175 2175);
PAINT GREEN (4175 2175);
DISPLAY INVISIBLE (4175 2175);
FORCEPROP 2 LAST CDS_LIB pure_quanta
J 0
(4100 2225);
DISPLAY INVISIBLE (4100 2225);
FORCEPROP 1 LAST PATH I59
J 0
(4100 2225);
DISPLAY 0.723404 (4100 2225);
PAINT GREEN (4100 2225);
DISPLAY INVISIBLE (4100 2225);
FORCEPROP 0 LAST CDS_LOCATION D42
J 0
(4025 2550);
DISPLAY 1.021277 (4025 2550);
DISPLAY INVISIBLE (4025 2550);
FORCEPROP 0 LAST $SEC 1
J 0
(4025 2550);
DISPLAY 0.680851 (4025 2550);
PAINT MONO (4025 2550);
DISPLAY INVISIBLE (4025 2550);
FORCEPROP 0 LAST CDS_SEC 1
J 0
(4025 2550);
DISPLAY 1.021277 (4025 2550);
DISPLAY INVISIBLE (4025 2550);
FORCEADD OFFPAGE..1
(525 725);
FORCEPROP 2 LAST $XR0 114 
J 0
(273 725);
DISPLAY 0.638298 (273 725);
PAINT MONO (273 725);
FORCEPROP 1 LAST COMMENT_BODY TRUE
J 0
(650 625);
DISPLAY 0.872340 (650 625);
PAINT GREEN (650 625);
DISPLAY INVISIBLE (650 625);
FORCEPROP 1 LAST OFFPAGE TRUE
J 0
(850 600);
DISPLAY 0.872340 (850 600);
PAINT GREEN (850 600);
DISPLAY INVISIBLE (850 600);
FORCEPROP 2 LAST CDS_LIB standard
J 0
(525 725);
PAINT MONO (525 725);
DISPLAY INVISIBLE (525 725);
FORCEPROP 2 LAST PATH I6
J 0
(250 775);
DISPLAY 1.021277 (250 775);
DISPLAY INVISIBLE (250 775);
FORCEADD UNIVERSAL_POWER..1
(4725 2400);
FORCEPROP 3 LASTPIN (4725 2350) SIG_NAME P3V3_AUX\g
J 0
(4735 2360);
DISPLAY 0.659574 (4735 2360);
PAINT MONO (4735 2360);
DISPLAY INVISIBLE (4735 2360);
FORCEPROP 1 LAST HDL_POWER P3V3_AUX
J 1
(4725 2450);
DISPLAY 0.872340 (4725 2450);
PAINT GREEN (4725 2450);
FORCEPROP 2 LAST CDS_LIB logical_power
J 0
(4725 2400);
DISPLAY INVISIBLE (4725 2400);
FORCEPROP 1 LAST PATH I60
J 0
(4775 2425);
DISPLAY 0.872340 (4775 2425);
PAINT AQUA (4775 2425);
DISPLAY INVISIBLE (4775 2425);
FORCEADD OFFPAGE..2
(5775 100);
FORCEPROP 2 LAST $XR0 214 
J 0
(5964 100);
DISPLAY 0.638298 (5964 100);
PAINT MONO (5964 100);
FORCEPROP 2 LAST CDS_LIB standard
J 0
(5775 100);
DISPLAY INVISIBLE (5775 100);
FORCEPROP 1 LAST OFFPAGE TRUE
J 0
(6100 -25);
DISPLAY 0.872340 (6100 -25);
PAINT GREEN (6100 -25);
DISPLAY INVISIBLE (6100 -25);
FORCEPROP 1 LAST COMMENT_BODY TRUE
J 0
(5730 5);
DISPLAY 0.872340 (5730 5);
PAINT GREEN (5730 5);
DISPLAY INVISIBLE (5730 5);
FORCEPROP 2 LAST PATH I61
J 0
(5975 150);
DISPLAY 1.021277 (5975 150);
DISPLAY INVISIBLE (5975 150);
FORCEADD OFFPAGE..2
(5775 725);
FORCEPROP 2 LAST $XR0 214 
J 0
(5964 725);
DISPLAY 0.638298 (5964 725);
PAINT MONO (5964 725);
FORCEPROP 1 LAST COMMENT_BODY TRUE
J 0
(5730 630);
DISPLAY 0.872340 (5730 630);
PAINT GREEN (5730 630);
DISPLAY INVISIBLE (5730 630);
FORCEPROP 1 LAST OFFPAGE TRUE
J 0
(6100 600);
DISPLAY 0.872340 (6100 600);
PAINT GREEN (6100 600);
DISPLAY INVISIBLE (6100 600);
FORCEPROP 2 LAST CDS_LIB standard
J 0
(5775 725);
DISPLAY INVISIBLE (5775 725);
FORCEPROP 2 LAST PATH I62
J 0
(5975 775);
DISPLAY 1.021277 (5975 775);
DISPLAY INVISIBLE (5975 775);
FORCEADD OFFPAGE..2
(5775 1350);
FORCEPROP 2 LAST $XR0 214 
J 0
(5964 1350);
DISPLAY 0.638298 (5964 1350);
PAINT MONO (5964 1350);
FORCEPROP 2 LAST CDS_LIB standard
J 0
(5775 1350);
DISPLAY INVISIBLE (5775 1350);
FORCEPROP 1 LAST OFFPAGE TRUE
J 0
(6100 1225);
DISPLAY 0.872340 (6100 1225);
PAINT GREEN (6100 1225);
DISPLAY INVISIBLE (6100 1225);
FORCEPROP 1 LAST COMMENT_BODY TRUE
J 0
(5730 1255);
DISPLAY 0.872340 (5730 1255);
PAINT GREEN (5730 1255);
DISPLAY INVISIBLE (5730 1255);
FORCEPROP 2 LAST PATH I63
J 0
(5975 1400);
DISPLAY 1.021277 (5975 1400);
DISPLAY INVISIBLE (5975 1400);
FORCEADD OFFPAGE..2
(5775 1975);
FORCEPROP 2 LAST $XR0 214 
J 0
(5964 1975);
DISPLAY 0.638298 (5964 1975);
PAINT MONO (5964 1975);
FORCEPROP 1 LAST COMMENT_BODY TRUE
J 0
(5730 1880);
DISPLAY 0.872340 (5730 1880);
PAINT GREEN (5730 1880);
DISPLAY INVISIBLE (5730 1880);
FORCEPROP 1 LAST OFFPAGE TRUE
J 0
(6100 1850);
DISPLAY 0.872340 (6100 1850);
PAINT GREEN (6100 1850);
DISPLAY INVISIBLE (6100 1850);
FORCEPROP 2 LAST CDS_LIB standard
J 0
(5775 1975);
DISPLAY INVISIBLE (5775 1975);
FORCEPROP 2 LAST PATH I64
J 0
(5975 2025);
DISPLAY 1.021277 (5975 2025);
DISPLAY INVISIBLE (5975 2025);
FORCEADD Q_RES..1
(4075 -2750);
FORCEPROP 1 LAST PART_NUMBER CS03322FB03
J 0
(3975 -2675);
DISPLAY 0.404255 (3975 -2675);
DISPLAY INVISIBLE (3975 -2675);
FORCEPROP 1 LAST TOLERANCE 1%
J 0
(4300 -2750);
DISPLAY 0.510638 (4300 -2750);
FORCEPROP 1 LAST VALUE 33.2
J 2
(4275 -2750);
DISPLAY 0.510638 (4275 -2750);
FORCEPROP 1 LAST LOCATION R2505
J 0
(3850 -2750);
DISPLAY 0.808511 (3850 -2750);
FORCEPROP 1 LASTPIN (3975 -2750) $PN 1
J 0
(3987 -2738);
DISPLAY 0.787234 (3987 -2738);
PAINT MONO (3987 -2738);
FORCEPROP 1 LASTPIN (4175 -2750) $PN 2
J 0
(4137 -2738);
DISPLAY 0.787234 (4137 -2738);
PAINT MONO (4137 -2738);
FORCEPROP 2 LAST CDS_LIB pure_quanta
J 0
(4075 -2750);
DISPLAY INVISIBLE (4075 -2750);
FORCEPROP 1 LAST PATH I65
J 0
(4025 -2600);
DISPLAY 0.978723 (4025 -2600);
PAINT WHITE (4025 -2600);
DISPLAY INVISIBLE (4025 -2600);
FORCEPROP 1 LAST MATERIAL CHIP
J 0
(3975 -2650);
DISPLAY 0.404255 (3975 -2650);
DISPLAY INVISIBLE (3975 -2650);
FORCEPROP 1 LAST PACK_TYPE 0402LF
J 0
(4075 -2650);
DISPLAY 0.404255 (4075 -2650);
DISPLAY INVISIBLE (4075 -2650);
FORCEPROP 1 LAST WATTAGE 1/16W
J 2
(4300 -2650);
DISPLAY 0.404255 (4300 -2650);
DISPLAY INVISIBLE (4300 -2650);
FORCEPROP 0 LAST $SEC 1
J 0
(3850 -2700);
DISPLAY 0.680851 (3850 -2700);
PAINT MONO (3850 -2700);
DISPLAY INVISIBLE (3850 -2700);
FORCEPROP 0 LAST CDS_SEC 1
J 0
(3850 -2700);
DISPLAY 1.021277 (3850 -2700);
DISPLAY INVISIBLE (3850 -2700);
FORCEADD Q_RES..1
(4075 -2125);
FORCEPROP 1 LAST PART_NUMBER CS03322FB03
J 0
(3975 -2050);
DISPLAY 0.404255 (3975 -2050);
DISPLAY INVISIBLE (3975 -2050);
FORCEPROP 1 LAST TOLERANCE 1%
J 0
(4300 -2125);
DISPLAY 0.510638 (4300 -2125);
FORCEPROP 1 LAST VALUE 33.2
J 2
(4275 -2125);
DISPLAY 0.510638 (4275 -2125);
FORCEPROP 1 LAST LOCATION R2504
J 0
(3850 -2125);
DISPLAY 0.808511 (3850 -2125);
FORCEPROP 1 LASTPIN (3975 -2125) $PN 1
J 0
(3987 -2113);
DISPLAY 0.787234 (3987 -2113);
PAINT MONO (3987 -2113);
FORCEPROP 1 LASTPIN (4175 -2125) $PN 2
J 0
(4137 -2113);
DISPLAY 0.787234 (4137 -2113);
PAINT MONO (4137 -2113);
FORCEPROP 2 LAST CDS_LIB pure_quanta
J 0
(4075 -2125);
DISPLAY INVISIBLE (4075 -2125);
FORCEPROP 1 LAST MATERIAL CHIP
J 0
(3975 -2025);
DISPLAY 0.404255 (3975 -2025);
DISPLAY INVISIBLE (3975 -2025);
FORCEPROP 1 LAST PACK_TYPE 0402LF
J 0
(4075 -2025);
DISPLAY 0.404255 (4075 -2025);
DISPLAY INVISIBLE (4075 -2025);
FORCEPROP 1 LAST WATTAGE 1/16W
J 2
(4300 -2025);
DISPLAY 0.404255 (4300 -2025);
DISPLAY INVISIBLE (4300 -2025);
FORCEPROP 1 LAST PATH I66
J 0
(4025 -1975);
DISPLAY 0.978723 (4025 -1975);
PAINT WHITE (4025 -1975);
DISPLAY INVISIBLE (4025 -1975);
FORCEPROP 0 LAST $SEC 1
J 0
(3850 -2075);
DISPLAY 0.680851 (3850 -2075);
PAINT MONO (3850 -2075);
DISPLAY INVISIBLE (3850 -2075);
FORCEPROP 0 LAST CDS_SEC 1
J 0
(3850 -2075);
DISPLAY 1.021277 (3850 -2075);
DISPLAY INVISIBLE (3850 -2075);
FORCEADD Q_RES..1
(4075 -1500);
FORCEPROP 1 LAST PART_NUMBER CS03322FB03
J 0
(3975 -1425);
DISPLAY 0.404255 (3975 -1425);
DISPLAY INVISIBLE (3975 -1425);
FORCEPROP 1 LAST TOLERANCE 1%
J 0
(4300 -1500);
DISPLAY 0.510638 (4300 -1500);
FORCEPROP 1 LAST VALUE 33.2
J 2
(4275 -1500);
DISPLAY 0.510638 (4275 -1500);
FORCEPROP 1 LAST LOCATION R2503
J 0
(3850 -1500);
DISPLAY 0.808511 (3850 -1500);
FORCEPROP 1 LASTPIN (3975 -1500) $PN 1
J 0
(3987 -1488);
DISPLAY 0.787234 (3987 -1488);
PAINT MONO (3987 -1488);
FORCEPROP 1 LASTPIN (4175 -1500) $PN 2
J 0
(4137 -1488);
DISPLAY 0.787234 (4137 -1488);
PAINT MONO (4137 -1488);
FORCEPROP 1 LAST PATH I67
J 0
(4025 -1350);
DISPLAY 0.978723 (4025 -1350);
PAINT WHITE (4025 -1350);
DISPLAY INVISIBLE (4025 -1350);
FORCEPROP 2 LAST CDS_LIB pure_quanta
J 0
(4075 -1500);
DISPLAY INVISIBLE (4075 -1500);
FORCEPROP 1 LAST MATERIAL CHIP
J 0
(3975 -1400);
DISPLAY 0.404255 (3975 -1400);
DISPLAY INVISIBLE (3975 -1400);
FORCEPROP 1 LAST PACK_TYPE 0402LF
J 0
(4075 -1400);
DISPLAY 0.404255 (4075 -1400);
DISPLAY INVISIBLE (4075 -1400);
FORCEPROP 1 LAST WATTAGE 1/16W
J 2
(4300 -1400);
DISPLAY 0.404255 (4300 -1400);
DISPLAY INVISIBLE (4300 -1400);
FORCEPROP 0 LAST $SEC 1
J 0
(3850 -1450);
DISPLAY 0.680851 (3850 -1450);
PAINT MONO (3850 -1450);
DISPLAY INVISIBLE (3850 -1450);
FORCEPROP 0 LAST CDS_SEC 1
J 0
(3850 -1450);
DISPLAY 1.021277 (3850 -1450);
DISPLAY INVISIBLE (3850 -1450);
FORCEADD Q_RES..1
(4075 -875);
FORCEPROP 1 LAST PART_NUMBER CS03322FB03
J 0
(3975 -800);
DISPLAY 0.404255 (3975 -800);
DISPLAY INVISIBLE (3975 -800);
FORCEPROP 1 LAST VALUE 33.2
J 2
(4275 -875);
DISPLAY 0.510638 (4275 -875);
FORCEPROP 1 LAST TOLERANCE 1%
J 0
(4300 -875);
DISPLAY 0.510638 (4300 -875);
FORCEPROP 1 LAST LOCATION R2502
J 0
(3850 -875);
DISPLAY 0.808511 (3850 -875);
FORCEPROP 1 LASTPIN (3975 -875) $PN 1
J 0
(3987 -863);
DISPLAY 0.787234 (3987 -863);
PAINT MONO (3987 -863);
FORCEPROP 1 LASTPIN (4175 -875) $PN 2
J 0
(4137 -863);
DISPLAY 0.787234 (4137 -863);
PAINT MONO (4137 -863);
FORCEPROP 1 LAST WATTAGE 1/16W
J 2
(4300 -775);
DISPLAY 0.404255 (4300 -775);
DISPLAY INVISIBLE (4300 -775);
FORCEPROP 1 LAST PACK_TYPE 0402LF
J 0
(4075 -775);
DISPLAY 0.404255 (4075 -775);
DISPLAY INVISIBLE (4075 -775);
FORCEPROP 1 LAST MATERIAL CHIP
J 0
(3975 -775);
DISPLAY 0.404255 (3975 -775);
DISPLAY INVISIBLE (3975 -775);
FORCEPROP 2 LAST CDS_LIB pure_quanta
J 0
(4075 -875);
DISPLAY INVISIBLE (4075 -875);
FORCEPROP 1 LAST PATH I68
J 0
(4025 -725);
DISPLAY 0.978723 (4025 -725);
PAINT WHITE (4025 -725);
DISPLAY INVISIBLE (4025 -725);
FORCEPROP 0 LAST $SEC 1
J 0
(3850 -825);
DISPLAY 0.680851 (3850 -825);
PAINT MONO (3850 -825);
DISPLAY INVISIBLE (3850 -825);
FORCEPROP 0 LAST CDS_SEC 1
J 0
(3850 -825);
DISPLAY 1.021277 (3850 -825);
DISPLAY INVISIBLE (3850 -825);
FORCEADD Q_RES..1
(4075 100);
FORCEPROP 1 LAST PART_NUMBER CS03322FB03
J 0
(3975 175);
DISPLAY 0.404255 (3975 175);
DISPLAY INVISIBLE (3975 175);
FORCEPROP 1 LAST VALUE 33.2
J 2
(4275 100);
DISPLAY 0.510638 (4275 100);
FORCEPROP 1 LAST TOLERANCE 1%
J 0
(4300 100);
DISPLAY 0.510638 (4300 100);
FORCEPROP 1 LAST LOCATION R2501
J 0
(3850 100);
DISPLAY 0.808511 (3850 100);
FORCEPROP 1 LASTPIN (3975 100) $PN 1
J 0
(3987 112);
DISPLAY 0.787234 (3987 112);
PAINT MONO (3987 112);
FORCEPROP 1 LASTPIN (4175 100) $PN 2
J 0
(4137 112);
DISPLAY 0.787234 (4137 112);
PAINT MONO (4137 112);
FORCEPROP 1 LAST WATTAGE 1/16W
J 2
(4300 200);
DISPLAY 0.404255 (4300 200);
DISPLAY INVISIBLE (4300 200);
FORCEPROP 1 LAST PACK_TYPE 0402LF
J 0
(4075 200);
DISPLAY 0.404255 (4075 200);
DISPLAY INVISIBLE (4075 200);
FORCEPROP 1 LAST MATERIAL CHIP
J 0
(3975 200);
DISPLAY 0.404255 (3975 200);
DISPLAY INVISIBLE (3975 200);
FORCEPROP 2 LAST CDS_LIB pure_quanta
J 0
(4075 100);
DISPLAY INVISIBLE (4075 100);
FORCEPROP 1 LAST PATH I69
J 0
(4025 250);
DISPLAY 0.978723 (4025 250);
PAINT WHITE (4025 250);
DISPLAY INVISIBLE (4025 250);
FORCEPROP 0 LAST $SEC 1
J 0
(3850 150);
DISPLAY 0.680851 (3850 150);
PAINT MONO (3850 150);
DISPLAY INVISIBLE (3850 150);
FORCEPROP 0 LAST CDS_SEC 1
J 0
(3850 150);
DISPLAY 1.021277 (3850 150);
DISPLAY INVISIBLE (3850 150);
FORCEADD OFFPAGE..1
(525 1350);
FORCEPROP 2 LAST $XR0 114 
J 0
(273 1350);
DISPLAY 0.638298 (273 1350);
PAINT MONO (273 1350);
FORCEPROP 2 LAST CDS_LIB standard
J 0
(525 1350);
PAINT MONO (525 1350);
DISPLAY INVISIBLE (525 1350);
FORCEPROP 1 LAST OFFPAGE TRUE
J 0
(850 1225);
DISPLAY 0.872340 (850 1225);
PAINT GREEN (850 1225);
DISPLAY INVISIBLE (850 1225);
FORCEPROP 1 LAST COMMENT_BODY TRUE
J 0
(650 1250);
DISPLAY 0.872340 (650 1250);
PAINT GREEN (650 1250);
DISPLAY INVISIBLE (650 1250);
FORCEPROP 2 LAST PATH I7
J 0
(250 1400);
DISPLAY 1.021277 (250 1400);
DISPLAY INVISIBLE (250 1400);
FORCEADD Q_RES..1
(4075 725);
FORCEPROP 1 LAST PART_NUMBER CS03322FB03
J 0
(3975 800);
DISPLAY 0.404255 (3975 800);
DISPLAY INVISIBLE (3975 800);
FORCEPROP 1 LAST VALUE 33.2
J 2
(4275 725);
DISPLAY 0.510638 (4275 725);
FORCEPROP 1 LAST TOLERANCE 1%
J 0
(4300 725);
DISPLAY 0.510638 (4300 725);
FORCEPROP 1 LAST LOCATION R2500
J 0
(3850 725);
DISPLAY 0.808511 (3850 725);
FORCEPROP 1 LASTPIN (3975 725) $PN 1
J 0
(3987 737);
DISPLAY 0.787234 (3987 737);
PAINT MONO (3987 737);
FORCEPROP 1 LASTPIN (4175 725) $PN 2
J 0
(4137 737);
DISPLAY 0.787234 (4137 737);
PAINT MONO (4137 737);
FORCEPROP 1 LAST WATTAGE 1/16W
J 2
(4300 825);
DISPLAY 0.404255 (4300 825);
DISPLAY INVISIBLE (4300 825);
FORCEPROP 1 LAST PACK_TYPE 0402LF
J 0
(4075 825);
DISPLAY 0.404255 (4075 825);
DISPLAY INVISIBLE (4075 825);
FORCEPROP 1 LAST MATERIAL CHIP
J 0
(3975 825);
DISPLAY 0.404255 (3975 825);
DISPLAY INVISIBLE (3975 825);
FORCEPROP 2 LAST CDS_LIB pure_quanta
J 0
(4075 725);
DISPLAY INVISIBLE (4075 725);
FORCEPROP 1 LAST PATH I70
J 0
(4025 875);
DISPLAY 0.978723 (4025 875);
PAINT WHITE (4025 875);
DISPLAY INVISIBLE (4025 875);
FORCEPROP 0 LAST $SEC 1
J 0
(3850 775);
DISPLAY 0.680851 (3850 775);
PAINT MONO (3850 775);
DISPLAY INVISIBLE (3850 775);
FORCEPROP 0 LAST CDS_SEC 1
J 0
(3850 775);
DISPLAY 1.021277 (3850 775);
DISPLAY INVISIBLE (3850 775);
FORCEADD Q_RES..1
(4075 1350);
FORCEPROP 1 LAST PART_NUMBER CS03322FB03
J 0
(3975 1425);
DISPLAY 0.404255 (3975 1425);
DISPLAY INVISIBLE (3975 1425);
FORCEPROP 1 LAST VALUE 33.2
J 2
(4275 1350);
DISPLAY 0.510638 (4275 1350);
FORCEPROP 1 LAST TOLERANCE 1%
J 0
(4300 1350);
DISPLAY 0.510638 (4300 1350);
FORCEPROP 1 LAST LOCATION R2499
J 0
(3850 1350);
DISPLAY 0.808511 (3850 1350);
FORCEPROP 1 LASTPIN (3975 1350) $PN 1
J 0
(3987 1362);
DISPLAY 0.787234 (3987 1362);
PAINT MONO (3987 1362);
FORCEPROP 1 LASTPIN (4175 1350) $PN 2
J 0
(4137 1362);
DISPLAY 0.787234 (4137 1362);
PAINT MONO (4137 1362);
FORCEPROP 1 LAST WATTAGE 1/16W
J 2
(4300 1450);
DISPLAY 0.404255 (4300 1450);
DISPLAY INVISIBLE (4300 1450);
FORCEPROP 1 LAST PACK_TYPE 0402LF
J 0
(4075 1450);
DISPLAY 0.404255 (4075 1450);
DISPLAY INVISIBLE (4075 1450);
FORCEPROP 1 LAST MATERIAL CHIP
J 0
(3975 1450);
DISPLAY 0.404255 (3975 1450);
DISPLAY INVISIBLE (3975 1450);
FORCEPROP 2 LAST CDS_LIB pure_quanta
J 0
(4075 1350);
DISPLAY INVISIBLE (4075 1350);
FORCEPROP 1 LAST PATH I71
J 0
(4025 1500);
DISPLAY 0.978723 (4025 1500);
PAINT WHITE (4025 1500);
DISPLAY INVISIBLE (4025 1500);
FORCEPROP 0 LAST $SEC 1
J 0
(3850 1400);
DISPLAY 0.680851 (3850 1400);
PAINT MONO (3850 1400);
DISPLAY INVISIBLE (3850 1400);
FORCEPROP 0 LAST CDS_SEC 1
J 0
(3850 1400);
DISPLAY 1.021277 (3850 1400);
DISPLAY INVISIBLE (3850 1400);
FORCEADD Q_RES..1
(4075 1975);
FORCEPROP 1 LAST PART_NUMBER CS03322FB03
J 0
(3975 2050);
DISPLAY 0.404255 (3975 2050);
DISPLAY INVISIBLE (3975 2050);
FORCEPROP 1 LAST VALUE 33.2
J 2
(4275 1975);
DISPLAY 0.510638 (4275 1975);
FORCEPROP 1 LAST TOLERANCE 1%
J 0
(4300 1975);
DISPLAY 0.510638 (4300 1975);
FORCEPROP 1 LAST LOCATION R2498
J 0
(3850 1975);
DISPLAY 0.808511 (3850 1975);
FORCEPROP 1 LASTPIN (3975 1975) $PN 1
J 0
(3987 1987);
DISPLAY 0.787234 (3987 1987);
PAINT MONO (3987 1987);
FORCEPROP 1 LASTPIN (4175 1975) $PN 2
J 0
(4137 1987);
DISPLAY 0.787234 (4137 1987);
PAINT MONO (4137 1987);
FORCEPROP 1 LAST PATH I72
J 0
(4025 2125);
DISPLAY 0.978723 (4025 2125);
PAINT WHITE (4025 2125);
DISPLAY INVISIBLE (4025 2125);
FORCEPROP 2 LAST CDS_LIB pure_quanta
J 0
(4075 1975);
DISPLAY INVISIBLE (4075 1975);
FORCEPROP 1 LAST MATERIAL CHIP
J 0
(3975 2075);
DISPLAY 0.404255 (3975 2075);
DISPLAY INVISIBLE (3975 2075);
FORCEPROP 1 LAST PACK_TYPE 0402LF
J 0
(4075 2075);
DISPLAY 0.404255 (4075 2075);
DISPLAY INVISIBLE (4075 2075);
FORCEPROP 1 LAST WATTAGE 1/16W
J 2
(4300 2075);
DISPLAY 0.404255 (4300 2075);
DISPLAY INVISIBLE (4300 2075);
FORCEPROP 0 LAST $SEC 1
J 0
(3850 2025);
DISPLAY 0.680851 (3850 2025);
PAINT MONO (3850 2025);
DISPLAY INVISIBLE (3850 2025);
FORCEPROP 0 LAST CDS_SEC 1
J 0
(3850 2025);
DISPLAY 1.021277 (3850 2025);
DISPLAY INVISIBLE (3850 2025);
FORCEADD OFFPAGE..1
(525 1975);
FORCEPROP 2 LAST $XR0 114 
J 0
(273 1975);
DISPLAY 0.638298 (273 1975);
PAINT MONO (273 1975);
FORCEPROP 1 LAST COMMENT_BODY TRUE
J 0
(650 1875);
DISPLAY 0.872340 (650 1875);
PAINT GREEN (650 1875);
DISPLAY INVISIBLE (650 1875);
FORCEPROP 1 LAST OFFPAGE TRUE
J 0
(850 1850);
DISPLAY 0.872340 (850 1850);
PAINT GREEN (850 1850);
DISPLAY INVISIBLE (850 1850);
FORCEPROP 2 LAST CDS_LIB standard
J 0
(525 1975);
PAINT MONO (525 1975);
DISPLAY INVISIBLE (525 1975);
FORCEPROP 2 LAST PATH I8
J 0
(250 2025);
DISPLAY 1.021277 (250 2025);
DISPLAY INVISIBLE (250 2025);
FORCEADD Q_RES..1
(1825 -2750);
FORCEPROP 1 LAST PART_NUMBER CS21002FB06
J 0
(1925 -2825);
DISPLAY 0.638298 (1925 -2825);
DISPLAY INVISIBLE (1925 -2825);
FORCEPROP 1 LAST WATTAGE 1/16W
J 2
(1775 -2875);
DISPLAY 0.638298 (1775 -2875);
FORCEPROP 1 LAST MATERIAL CHIP
J 0
(1800 -2875);
DISPLAY 0.638298 (1800 -2875);
FORCEPROP 1 LAST PACK_TYPE 0402LF
J 0
(2050 -2875);
DISPLAY 0.638298 (2050 -2875);
FORCEPROP 1 LAST VALUE 1K
J 2
(1775 -2825);
DISPLAY 0.638298 (1775 -2825);
FORCEPROP 1 LAST TOLERANCE 1%
J 0
(1800 -2825);
DISPLAY 0.638298 (1800 -2825);
FORCEPROP 1 LAST $LOCATION R2497
J 0
(1575 -2750);
DISPLAY 0.787234 (1575 -2750);
FORCEPROP 1 LASTPIN (1725 -2750) $PN 1
J 0
(1737 -2738);
DISPLAY 0.787234 (1737 -2738);
PAINT MONO (1737 -2738);
FORCEPROP 1 LASTPIN (1925 -2750) $PN 2
J 0
(1887 -2738);
DISPLAY 0.787234 (1887 -2738);
PAINT MONO (1887 -2738);
FORCEPROP 1 LAST PATH I9
J 0
(1775 -2600);
DISPLAY 0.978723 (1775 -2600);
PAINT WHITE (1775 -2600);
DISPLAY INVISIBLE (1775 -2600);
FORCEPROP 2 LAST CDS_LIB pure_quanta
J 0
(1825 -2750);
DISPLAY INVISIBLE (1825 -2750);
FORCEPROP 0 LAST CDS_LOCATION R2497
J 0
(2000 -2600);
DISPLAY 1.021277 (2000 -2600);
DISPLAY INVISIBLE (2000 -2600);
FORCEPROP 0 LAST $SEC 1
J 0
(1575 -2700);
DISPLAY 0.680851 (1575 -2700);
PAINT MONO (1575 -2700);
DISPLAY INVISIBLE (1575 -2700);
FORCEPROP 0 LAST CDS_SEC 1
J 0
(2000 -2600);
DISPLAY 1.021277 (2000 -2600);
DISPLAY INVISIBLE (2000 -2600);
FORCEADD QUANTA_TITLE_BLOCK_C..1
(7975 -3775);
FORCEPROP 0 LAST CDS_CON_LAST_MODIFIED Fri Aug 25 14:01:36 2023
J 0
(6090 -3760);
DISPLAY INVISIBLE (6090 -3760);
FORCEPROP 1 LAST CUSTOM_TXT_CDS <CON_LAST_MODIFIED>
J 0
(6090 -3760);
DISPLAY 0.978723 (6090 -3760);
FORCEPROP 2 LAST CUSTOM_TXT_CDS <XR_PAGE_TITLE>
J 0
(85 1475);
DISPLAY 0.638298 (85 1475);
PAINT PINK (85 1475);
DISPLAY INVISIBLE (85 1475);
FORCEPROP 1 LAST CUSTOM_TXT_CDS <NAME_2>
J 0
(4800 -3725);
FORCEPROP 1 LAST CUSTOM_TXT_CDS <NAME_1>
J 0
(4800 -3600);
FORCEPROP 1 LAST CUSTOM_TXT_CDS <Q_NUMBER>
J 0
(6572 -3672);
DISPLAY 1.212766 (6572 -3672);
FORCEPROP 1 LAST CUSTOM_TXT_CDS <Q_PROJ>
J 0
(5593 -3673);
DISPLAY 1.212766 (5593 -3673);
FORCEPROP 1 LAST CUSTOM_TXT_CDS <Q_REV>
J 0
(7791 -3672);
DISPLAY 1.212766 (7791 -3672);
FORCEPROP 1 LAST CUSTOM_TXT_CDS <CON_PAGE_NUM> OF <CON_TOTAL_PAGES>
J 0
(7529 -3757);
DISPLAY 0.978723 (7529 -3757);
FORCEPROP 1 LAST Q_TITLE DDR5 - PWRGD
J 0
(-1391 -3749);
DISPLAY 2.446809 (-1391 -3749);
PAINT GREEN (-1391 -3749);
FORCEPROP 1 LAST Q_DEPT 
J 1
(4212 -3726);
DISPLAY 1.957447 (4212 -3726);
PAINT GREEN (4212 -3726);
FORCEPROP 2 LAST CDS_XR_PAGE_TITLE CR-115 : @S9S_MB_2U_LIB.S9S_MB_2U(SCH_1):PAGE115
J 0
(85 1475);
DISPLAY 0.638298 (85 1475);
PAINT PINK (85 1475);
DISPLAY INVISIBLE (85 1475);
FORCEPROP 2 LAST PAGE_BORDER TRUE
J 0
(85 1475);
DISPLAY 0.638298 (85 1475);
PAINT PINK (85 1475);
DISPLAY INVISIBLE (85 1475);
FORCEPROP 1 LAST COMMENT_BODY TRUE
J 0
(7987 -3788);
DISPLAY 0.978723 (7987 -3788);
PAINT GREEN (7987 -3788);
DISPLAY INVISIBLE (7987 -3788);
FORCEPROP 1 LAST CDS_LMAN_SYM_OUTLINE -9475,6775,100,-125
J 0
(7975 -3775);
DISPLAY 0.468085 (7975 -3775);
PAINT GREEN (7975 -3775);
DISPLAY INVISIBLE (7975 -3775);
FORCEPROP 2 LAST CDS_LIB pure_quanta
J 0
(7975 -3775);
DISPLAY INVISIBLE (7975 -3775);
WIRE 16 -1 (4725 -2375)(4725 -2500);
WIRE 16 -1 (4725 -1125)(4725 -1250);
WIRE 16 -1 (4725 -500)(4725 -625);
WIRE 16 -1 (4725 1725)(4725 1600);
WIRE 16 -1 (4725 475)(4725 350);
WIRE 16 -1 (4725 1100)(4725 975);
WIRE 16 -1 (4725 -1750)(4725 -1875);
WIRE 16 -1 (1400 475)(1400 350);
WIRE 16 -1 (1400 1725)(1400 1600);
WIRE 16 -1 (4725 2350)(4725 2225);
WIRE 16 -1 (1400 -2375)(1400 -2500);
WIRE 16 -1 (1400 -1750)(1400 -1875);
WIRE 16 -1 (1400 -1125)(1400 -1250);
WIRE 16 -1 (1400 -500)(1400 -625);
WIRE 16 -1 (1400 1100)(1400 975);
WIRE 16 -1 (1400 2350)(1400 2225);
WIRE 16 -1 (1725 975)(1400 975);
WIRE 16 -1 (4225 -1875)(4725 -1875);
WIRE 16 -1 (4175 -2125)(5725 -2125);
FORCEPROP 2 LAST SIG_NAME PWRGD_FAIL_CPU1_EF_R
J 0
(4890 -2115);
DISPLAY 0.680851 (4890 -2115);
PAINT WHITE (4890 -2115);
WIRE 16 -1 (2375 -1875)(1925 -1875);
WIRE 16 -1 (2375 -2125)(1925 -2125);
WIRE 16 -1 (2375 -2125)(2375 -1875);
WIRE 16 -1 (3750 -2125)(2375 -2125);
FORCEPROP 2 LAST SIG_NAME PWRGD_FAIL_CPU1_EF_R1
J 0
(2740 -2115);
DISPLAY 0.680851 (2740 -2115);
PAINT WHITE (2740 -2115);
WIRE 16 -1 (3750 -2125)(3975 -2125);
WIRE 16 -1 (3750 -1875)(3750 -2125);
WIRE 16 -1 (3975 -1875)(3750 -1875);
WIRE 16 -1 (1725 -1875)(1400 -1875);
WIRE 16 -1 (4175 -1500)(5725 -1500);
FORCEPROP 2 LAST SIG_NAME PWRGD_FAIL_CPU1_CD_R
J 0
(4890 -1490);
DISPLAY 0.680851 (4890 -1490);
PAINT WHITE (4890 -1490);
WIRE 16 -1 (4225 -1250)(4725 -1250);
WIRE 16 -1 (4175 -875)(5725 -875);
FORCEPROP 2 LAST SIG_NAME PWRGD_FAIL_CPU1_AB_R
J 0
(4890 -865);
DISPLAY 0.680851 (4890 -865);
PAINT WHITE (4890 -865);
WIRE 16 -1 (4225 -625)(4725 -625);
WIRE 16 -1 (4175 100)(5725 100);
FORCEPROP 2 LAST SIG_NAME PWRGD_FAIL_CPU0_GH_R
J 0
(4890 110);
DISPLAY 0.680851 (4890 110);
PAINT WHITE (4890 110);
WIRE 16 -1 (4175 725)(5725 725);
FORCEPROP 2 LAST SIG_NAME PWRGD_FAIL_CPU0_EF_R
J 0
(4890 735);
DISPLAY 0.680851 (4890 735);
PAINT WHITE (4890 735);
WIRE 16 -1 (4175 1975)(5725 1975);
FORCEPROP 2 LAST SIG_NAME PWRGD_FAIL_CPU0_AB_R
J 0
(4865 1985);
DISPLAY 0.680851 (4865 1985);
PAINT WHITE (4865 1985);
WIRE 16 -1 (4225 1600)(4725 1600);
WIRE 16 -1 (4175 1350)(5725 1350);
FORCEPROP 2 LAST SIG_NAME PWRGD_FAIL_CPU0_CD_R
J 0
(4890 1360);
DISPLAY 0.680851 (4890 1360);
PAINT WHITE (4890 1360);
WIRE 16 -1 (2375 -1250)(1925 -1250);
WIRE 16 -1 (3975 -1250)(3750 -1250);
WIRE 16 -1 (2375 -1500)(1925 -1500);
WIRE 16 -1 (2375 -1500)(2375 -1250);
WIRE 16 -1 (3750 -1500)(2375 -1500);
FORCEPROP 2 LAST SIG_NAME PWRGD_FAIL_CPU1_CD_R1
J 0
(2740 -1490);
DISPLAY 0.680851 (2740 -1490);
PAINT WHITE (2740 -1490);
WIRE 16 -1 (3750 -1250)(3750 -1500);
WIRE 16 -1 (3750 -1500)(3975 -1500);
WIRE 16 -1 (2375 -625)(1925 -625);
WIRE 16 -1 (3975 -625)(3750 -625);
WIRE 16 -1 (2375 -875)(1925 -875);
WIRE 16 -1 (2375 -875)(2375 -625);
WIRE 16 -1 (3750 -875)(2375 -875);
FORCEPROP 2 LAST SIG_NAME PWRGD_FAIL_CPU1_AB_R1
J 0
(2740 -865);
DISPLAY 0.680851 (2740 -865);
PAINT WHITE (2740 -865);
WIRE 16 -1 (3750 -625)(3750 -875);
WIRE 16 -1 (3750 -875)(3975 -875);
WIRE 16 -1 (2375 -2500)(1925 -2500);
WIRE 16 -1 (2375 -2750)(1925 -2750);
WIRE 16 -1 (2375 -2750)(2375 -2500);
WIRE 16 -1 (3750 -2750)(2375 -2750);
FORCEPROP 2 LAST SIG_NAME PWRGD_FAIL_CPU1_GH_R1
J 0
(2740 -2740);
DISPLAY 0.680851 (2740 -2740);
PAINT WHITE (2740 -2740);
WIRE 16 -1 (3750 -2750)(3975 -2750);
WIRE 16 -1 (3975 -2500)(3750 -2500);
WIRE 16 -1 (3750 -2500)(3750 -2750);
WIRE 16 -1 (4175 -2750)(5725 -2750);
FORCEPROP 2 LAST SIG_NAME PWRGD_FAIL_CPU1_GH_R
J 0
(4890 -2740);
DISPLAY 0.680851 (4890 -2740);
PAINT WHITE (4890 -2740);
WIRE 16 -1 (4225 -2500)(4725 -2500);
WIRE 16 -1 (2375 350)(1925 350);
WIRE 16 -1 (3975 350)(3750 350);
WIRE 16 -1 (2375 100)(1925 100);
WIRE 16 -1 (2375 100)(2375 350);
WIRE 16 -1 (3750 100)(2375 100);
FORCEPROP 2 LAST SIG_NAME PWRGD_FAIL_CPU0_GH_R1
J 0
(2740 110);
DISPLAY 0.680851 (2740 110);
PAINT WHITE (2740 110);
WIRE 16 -1 (3750 350)(3750 100);
WIRE 16 -1 (3750 100)(3975 100);
WIRE 16 -1 (4225 350)(4725 350);
WIRE 16 -1 (2375 975)(1925 975);
WIRE 16 -1 (3975 975)(3750 975);
WIRE 16 -1 (2375 725)(1925 725);
WIRE 16 -1 (2375 725)(2375 975);
WIRE 16 -1 (3750 725)(2375 725);
FORCEPROP 2 LAST SIG_NAME PWRGD_FAIL_CPU0_EF_R1
J 0
(2740 735);
DISPLAY 0.680851 (2740 735);
PAINT WHITE (2740 735);
WIRE 16 -1 (3750 975)(3750 725);
WIRE 16 -1 (3750 725)(3975 725);
WIRE 16 -1 (4225 975)(4725 975);
WIRE 16 -1 (2375 1600)(1925 1600);
WIRE 16 -1 (2375 1350)(1925 1350);
WIRE 16 -1 (2375 1350)(2375 1600);
WIRE 16 -1 (3750 1350)(2375 1350);
FORCEPROP 2 LAST SIG_NAME PWRGD_FAIL_CPU0_CD_R1
J 0
(2740 1360);
DISPLAY 0.680851 (2740 1360);
PAINT WHITE (2740 1360);
WIRE 16 -1 (3750 1350)(3975 1350);
WIRE 16 -1 (3975 1600)(3750 1600);
WIRE 16 -1 (3750 1600)(3750 1350);
WIRE 16 -1 (2375 2225)(1925 2225);
WIRE 16 -1 (2375 1975)(1925 1975);
WIRE 16 -1 (2375 1975)(2375 2225);
WIRE 16 -1 (3750 1975)(2375 1975);
FORCEPROP 2 LAST SIG_NAME PWRGD_FAIL_CPU0_AB_R1
J 0
(2740 1985);
DISPLAY 0.680851 (2740 1985);
PAINT WHITE (2740 1985);
WIRE 16 -1 (3750 1975)(3975 1975);
WIRE 16 -1 (3750 2225)(3750 1975);
WIRE 16 -1 (3975 2225)(3750 2225);
WIRE 16 -1 (1725 350)(1400 350);
WIRE 16 -1 (575 725)(1725 725);
FORCEPROP 2 LAST SIG_NAME PWRGD_FAIL_CPU0_EF
J 0
(715 735);
DISPLAY 0.680851 (715 735);
PAINT WHITE (715 735);
WIRE 16 -1 (575 1350)(1725 1350);
FORCEPROP 2 LAST SIG_NAME PWRGD_FAIL_CPU0_CD
J 0
(715 1360);
DISPLAY 0.680851 (715 1360);
PAINT WHITE (715 1360);
WIRE 16 -1 (1725 -2500)(1400 -2500);
WIRE 16 -1 (1725 -1250)(1400 -1250);
WIRE 16 -1 (1725 -625)(1400 -625);
WIRE 16 -1 (1725 1600)(1400 1600);
WIRE 16 -1 (1725 2225)(1400 2225);
WIRE 16 -1 (575 -1500)(1725 -1500);
FORCEPROP 2 LAST SIG_NAME PWRGD_FAIL_CPU1_CD
J 0
(715 -1490);
DISPLAY 0.680851 (715 -1490);
PAINT WHITE (715 -1490);
WIRE 16 -1 (575 -2750)(1725 -2750);
FORCEPROP 2 LAST SIG_NAME PWRGD_FAIL_CPU1_GH
J 0
(715 -2740);
DISPLAY 0.680851 (715 -2740);
PAINT WHITE (715 -2740);
WIRE 16 -1 (575 -2125)(1725 -2125);
FORCEPROP 2 LAST SIG_NAME PWRGD_FAIL_CPU1_EF
J 0
(715 -2115);
DISPLAY 0.680851 (715 -2115);
PAINT WHITE (715 -2115);
WIRE 16 -1 (575 -875)(1725 -875);
FORCEPROP 2 LAST SIG_NAME PWRGD_FAIL_CPU1_AB
J 0
(715 -865);
DISPLAY 0.680851 (715 -865);
PAINT WHITE (715 -865);
WIRE 16 -1 (575 100)(1725 100);
FORCEPROP 2 LAST SIG_NAME PWRGD_FAIL_CPU0_GH
J 0
(715 110);
DISPLAY 0.680851 (715 110);
PAINT WHITE (715 110);
WIRE 16 -1 (575 1975)(1725 1975);
FORCEPROP 2 LAST SIG_NAME PWRGD_FAIL_CPU0_AB
J 0
(715 1985);
DISPLAY 0.680851 (715 1985);
PAINT WHITE (715 1985);
WIRE 16 -1 (4225 2225)(4725 2225);
DOT 1 (3750 -2125);
DOT 1 (2375 725);
DOT 1 (2375 1350);
DOT 1 (3750 1975);
DOT 1 (3750 1350);
DOT 1 (3750 725);
DOT 1 (3750 100);
DOT 1 (2375 1975);
DOT 1 (2375 100);
DOT 1 (3750 -875);
DOT 1 (3750 -1500);
DOT 1 (3750 -2750);
DOT 1 (2375 -875);
DOT 1 (2375 -1500);
DOT 1 (2375 -2125);
DOT 1 (2375 -2750);
FORCENOTE
20211206 MODIFY FOR GT
(-1250 2675) 0;
DISPLAY LEFT (-1250 2675);
DISPLAY 2.510638 (-1250 2675);
PAINT PINK (-1250 2675);
QUIT
